(kicad_sch (version 20230121) (generator eeschema)

  (paper "A3")

  (title_block
    (title "ECP5 - Datacenter Secure Control Module (DC-SCM)")
    (date "2024-07-15")
    (rev "1.2.1")
  )

  (junction (at 133.35 115.57) (diameter 0) (color 0 0 0 0)
  )
  (junction (at 118.11 102.87) (diameter 0) (color 0 0 0 0)
  )
  (junction (at 58.42 186.69) (diameter 0) (color 0 0 0 0)
  )
  (junction (at 267.97 107.95) (diameter 0) (color 0 0 0 0)
  )
  (junction (at 133.35 125.73) (diameter 0) (color 0 0 0 0)
  )
  (junction (at 125.73 115.57) (diameter 0) (color 0 0 0 0)
  )
  (junction (at 140.97 92.71) (diameter 0) (color 0 0 0 0)
  )
  (junction (at 231.14 171.45) (diameter 0) (color 0 0 0 0)
  )
  (junction (at 40.64 186.69) (diameter 0) (color 0 0 0 0)
  )
  (junction (at 110.49 92.71) (diameter 0) (color 0 0 0 0)
  )
  (junction (at 295.91 85.09) (diameter 0) (color 0 0 0 0)
  )
  (junction (at 308.61 97.79) (diameter 0) (color 0 0 0 0)
  )
  (junction (at 186.69 194.31) (diameter 0) (color 0 0 0 0)
  )
  (junction (at 139.7 115.57) (diameter 0) (color 0 0 0 0)
  )
  (junction (at 293.37 140.97) (diameter 0) (color 0 0 0 0)
  )
  (junction (at 287.02 140.97) (diameter 0) (color 0 0 0 0)
  )
  (junction (at 133.35 92.71) (diameter 0) (color 0 0 0 0)
  )
  (junction (at 276.86 85.09) (diameter 0) (color 0 0 0 0)
  )
  (junction (at 111.76 186.69) (diameter 0) (color 0 0 0 0)
  )
  (junction (at 83.82 186.69) (diameter 0) (color 0 0 0 0)
  )
  (junction (at 276.86 97.79) (diameter 0) (color 0 0 0 0)
  )
  (junction (at 257.81 85.09) (diameter 0) (color 0 0 0 0)
  )
  (junction (at 49.53 186.69) (diameter 0) (color 0 0 0 0)
  )
  (junction (at 118.11 92.71) (diameter 0) (color 0 0 0 0)
  )
  (junction (at 102.87 186.69) (diameter 0) (color 0 0 0 0)
  )
  (junction (at 110.49 102.87) (diameter 0) (color 0 0 0 0)
  )
  (junction (at 302.26 85.09) (diameter 0) (color 0 0 0 0)
  )
  (junction (at 287.02 130.81) (diameter 0) (color 0 0 0 0)
  )
  (junction (at 264.16 97.79) (diameter 0) (color 0 0 0 0)
  )
  (junction (at 125.73 102.87) (diameter 0) (color 0 0 0 0)
  )
  (junction (at 74.93 186.69) (diameter 0) (color 0 0 0 0)
  )
  (junction (at 125.73 125.73) (diameter 0) (color 0 0 0 0)
  )
  (junction (at 287.02 119.38) (diameter 0) (color 0 0 0 0)
  )
  (junction (at 293.37 130.81) (diameter 0) (color 0 0 0 0)
  )
  (junction (at 274.32 119.38) (diameter 0) (color 0 0 0 0)
  )
  (junction (at 283.21 85.09) (diameter 0) (color 0 0 0 0)
  )
  (junction (at 295.91 97.79) (diameter 0) (color 0 0 0 0)
  )
  (junction (at 92.71 186.69) (diameter 0) (color 0 0 0 0)
  )
  (junction (at 308.61 85.09) (diameter 0) (color 0 0 0 0)
  )
  (junction (at 270.51 97.79) (diameter 0) (color 0 0 0 0)
  )
  (junction (at 280.67 119.38) (diameter 0) (color 0 0 0 0)
  )
  (junction (at 264.16 85.09) (diameter 0) (color 0 0 0 0)
  )
  (junction (at 66.04 186.69) (diameter 0) (color 0 0 0 0)
  )
  (junction (at 280.67 107.95) (diameter 0) (color 0 0 0 0)
  )
  (junction (at 283.21 97.79) (diameter 0) (color 0 0 0 0)
  )
  (junction (at 270.51 85.09) (diameter 0) (color 0 0 0 0)
  )
  (junction (at 231.14 168.91) (diameter 0) (color 0 0 0 0)
  )
  (junction (at 120.65 186.69) (diameter 0) (color 0 0 0 0)
  )
  (junction (at 125.73 92.71) (diameter 0) (color 0 0 0 0)
  )
  (junction (at 302.26 97.79) (diameter 0) (color 0 0 0 0)
  )
  (junction (at 279.4 130.81) (diameter 0) (color 0 0 0 0)
  )
  (junction (at 289.56 97.79) (diameter 0) (color 0 0 0 0)
  )
  (junction (at 133.35 102.87) (diameter 0) (color 0 0 0 0)
  )
  (junction (at 289.56 85.09) (diameter 0) (color 0 0 0 0)
  )
  (junction (at 287.02 107.95) (diameter 0) (color 0 0 0 0)
  )
  (junction (at 196.85 194.31) (diameter 0) (color 0 0 0 0)
  )
  (junction (at 274.32 107.95) (diameter 0) (color 0 0 0 0)
  )
  (junction (at 116.84 139.7) (diameter 0) (color 0 0 0 0)
  )

  (no_connect (at 228.6 120.65))
  (no_connect (at 184.15 171.45))

  (wire (pts (xy 186.69 193.04) (xy 186.69 194.31))
    (stroke (width 0) (type default))
  )
  (wire (pts (xy 302.26 97.79) (xy 308.61 97.79))
    (stroke (width 0) (type default))
  )
  (wire (pts (xy 116.84 139.7) (xy 116.84 140.97))
    (stroke (width 0) (type default))
  )
  (wire (pts (xy 287.02 115.57) (xy 287.02 119.38))
    (stroke (width 0) (type default))
  )
  (wire (pts (xy 231.14 168.91) (xy 231.14 171.45))
    (stroke (width 0) (type default))
  )
  (wire (pts (xy 289.56 85.09) (xy 295.91 85.09))
    (stroke (width 0) (type default))
  )
  (wire (pts (xy 147.32 119.38) (xy 147.32 139.7))
    (stroke (width 0) (type default))
  )
  (wire (pts (xy 279.4 140.97) (xy 287.02 140.97))
    (stroke (width 0) (type default))
  )
  (wire (pts (xy 304.8 107.95) (xy 309.88 107.95))
    (stroke (width 0) (type default))
  )
  (wire (pts (xy 334.01 137.16) (xy 355.6 137.16))
    (stroke (width 0) (type default))
  )
  (wire (pts (xy 308.61 93.98) (xy 308.61 97.79))
    (stroke (width 0) (type default))
  )
  (wire (pts (xy 289.56 85.09) (xy 289.56 88.9))
    (stroke (width 0) (type default))
  )
  (wire (pts (xy 184.15 134.62) (xy 163.83 134.62))
    (stroke (width 0) (type default))
  )
  (wire (pts (xy 196.85 199.39) (xy 196.85 201.93))
    (stroke (width 0) (type default))
  )
  (wire (pts (xy 58.42 196.85) (xy 58.42 220.98))
    (stroke (width 0) (type default))
  )
  (wire (pts (xy 184.15 161.29) (xy 163.83 161.29))
    (stroke (width 0) (type default))
  )
  (wire (pts (xy 162.56 111.76) (xy 162.56 92.71))
    (stroke (width 0) (type default))
  )
  (wire (pts (xy 307.34 130.81) (xy 309.88 130.81))
    (stroke (width 0) (type default))
  )
  (wire (pts (xy 147.32 139.7) (xy 116.84 139.7))
    (stroke (width 0) (type default))
  )
  (wire (pts (xy 246.38 128.27) (xy 228.6 128.27))
    (stroke (width 0) (type default))
  )
  (wire (pts (xy 295.91 93.98) (xy 295.91 97.79))
    (stroke (width 0) (type default))
  )
  (wire (pts (xy 287.02 107.95) (xy 287.02 110.49))
    (stroke (width 0) (type default))
  )
  (wire (pts (xy 120.65 196.85) (xy 120.65 201.93))
    (stroke (width 0) (type default))
  )
  (wire (pts (xy 308.61 85.09) (xy 308.61 88.9))
    (stroke (width 0) (type default))
  )
  (wire (pts (xy 74.93 214.63) (xy 132.08 214.63))
    (stroke (width 0) (type default))
  )
  (wire (pts (xy 231.14 162.56) (xy 231.14 161.29))
    (stroke (width 0) (type default))
  )
  (wire (pts (xy 125.73 92.71) (xy 133.35 92.71))
    (stroke (width 0) (type default))
  )
  (wire (pts (xy 133.35 125.73) (xy 139.7 125.73))
    (stroke (width 0) (type default))
  )
  (wire (pts (xy 256.54 118.11) (xy 256.54 130.81))
    (stroke (width 0) (type default))
  )
  (wire (pts (xy 231.14 167.64) (xy 231.14 168.91))
    (stroke (width 0) (type default))
  )
  (wire (pts (xy 267.97 115.57) (xy 267.97 119.38))
    (stroke (width 0) (type default))
  )
  (wire (pts (xy 184.15 111.76) (xy 162.56 111.76))
    (stroke (width 0) (type default))
  )
  (wire (pts (xy 111.76 139.7) (xy 116.84 139.7))
    (stroke (width 0) (type default))
  )
  (wire (pts (xy 110.49 92.71) (xy 110.49 95.25))
    (stroke (width 0) (type default))
  )
  (wire (pts (xy 238.76 85.09) (xy 257.81 85.09))
    (stroke (width 0) (type default))
  )
  (wire (pts (xy 140.97 224.79) (xy 49.53 224.79))
    (stroke (width 0) (type default))
  )
  (wire (pts (xy 274.32 107.95) (xy 280.67 107.95))
    (stroke (width 0) (type default))
  )
  (wire (pts (xy 133.35 123.19) (xy 133.35 125.73))
    (stroke (width 0) (type default))
  )
  (wire (pts (xy 308.61 97.79) (xy 308.61 99.06))
    (stroke (width 0) (type default))
  )
  (wire (pts (xy 293.37 132.08) (xy 293.37 130.81))
    (stroke (width 0) (type default))
  )
  (wire (pts (xy 139.7 123.19) (xy 139.7 125.73))
    (stroke (width 0) (type default))
  )
  (wire (pts (xy 83.82 212.09) (xy 132.08 212.09))
    (stroke (width 0) (type default))
  )
  (wire (pts (xy 186.69 194.31) (xy 186.69 195.58))
    (stroke (width 0) (type default))
  )
  (wire (pts (xy 124.46 199.39) (xy 132.08 199.39))
    (stroke (width 0) (type default))
  )
  (wire (pts (xy 334.01 146.05) (xy 355.6 146.05))
    (stroke (width 0) (type default))
  )
  (wire (pts (xy 287.02 130.81) (xy 293.37 130.81))
    (stroke (width 0) (type default))
  )
  (wire (pts (xy 66.04 196.85) (xy 66.04 218.44))
    (stroke (width 0) (type default))
  )
  (wire (pts (xy 283.21 85.09) (xy 283.21 88.9))
    (stroke (width 0) (type default))
  )
  (wire (pts (xy 40.64 186.69) (xy 40.64 191.77))
    (stroke (width 0) (type default))
  )
  (wire (pts (xy 132.08 207.01) (xy 102.87 207.01))
    (stroke (width 0) (type default))
  )
  (wire (pts (xy 49.53 196.85) (xy 49.53 224.79))
    (stroke (width 0) (type default))
  )
  (wire (pts (xy 334.01 143.51) (xy 355.6 143.51))
    (stroke (width 0) (type default))
  )
  (wire (pts (xy 184.15 121.92) (xy 163.83 121.92))
    (stroke (width 0) (type default))
  )
  (wire (pts (xy 116.84 146.05) (xy 116.84 147.32))
    (stroke (width 0) (type default))
  )
  (wire (pts (xy 102.87 186.69) (xy 92.71 186.69))
    (stroke (width 0) (type default))
  )
  (wire (pts (xy 293.37 129.54) (xy 293.37 130.81))
    (stroke (width 0) (type default))
  )
  (wire (pts (xy 295.91 85.09) (xy 302.26 85.09))
    (stroke (width 0) (type default))
  )
  (wire (pts (xy 270.51 97.79) (xy 276.86 97.79))
    (stroke (width 0) (type default))
  )
  (wire (pts (xy 248.92 153.67) (xy 228.6 153.67))
    (stroke (width 0) (type default))
  )
  (wire (pts (xy 334.01 130.81) (xy 355.6 130.81))
    (stroke (width 0) (type default))
  )
  (wire (pts (xy 133.35 92.71) (xy 140.97 92.71))
    (stroke (width 0) (type default))
  )
  (wire (pts (xy 184.15 165.1) (xy 163.83 165.1))
    (stroke (width 0) (type default))
  )
  (wire (pts (xy 110.49 102.87) (xy 118.11 102.87))
    (stroke (width 0) (type default))
  )
  (wire (pts (xy 334.01 127) (xy 355.6 127))
    (stroke (width 0) (type default))
  )
  (wire (pts (xy 110.49 92.71) (xy 118.11 92.71))
    (stroke (width 0) (type default))
  )
  (wire (pts (xy 107.95 115.57) (xy 101.6 115.57))
    (stroke (width 0) (type default))
  )
  (wire (pts (xy 228.6 118.11) (xy 256.54 118.11))
    (stroke (width 0) (type default))
  )
  (wire (pts (xy 74.93 196.85) (xy 74.93 214.63))
    (stroke (width 0) (type default))
  )
  (wire (pts (xy 228.6 168.91) (xy 231.14 168.91))
    (stroke (width 0) (type default))
  )
  (wire (pts (xy 246.38 134.62) (xy 228.6 134.62))
    (stroke (width 0) (type default))
  )
  (wire (pts (xy 228.6 111.76) (xy 238.76 111.76))
    (stroke (width 0) (type default))
  )
  (wire (pts (xy 246.38 125.73) (xy 228.6 125.73))
    (stroke (width 0) (type default))
  )
  (wire (pts (xy 49.53 186.69) (xy 40.64 186.69))
    (stroke (width 0) (type default))
  )
  (wire (pts (xy 330.2 163.83) (xy 330.2 166.37))
    (stroke (width 0) (type default))
  )
  (wire (pts (xy 125.73 123.19) (xy 125.73 125.73))
    (stroke (width 0) (type default))
  )
  (wire (pts (xy 140.97 100.33) (xy 140.97 102.87))
    (stroke (width 0) (type default))
  )
  (wire (pts (xy 110.49 100.33) (xy 110.49 102.87))
    (stroke (width 0) (type default))
  )
  (wire (pts (xy 393.7 132.08) (xy 383.54 132.08))
    (stroke (width 0) (type default))
  )
  (wire (pts (xy 302.26 85.09) (xy 302.26 88.9))
    (stroke (width 0) (type default))
  )
  (wire (pts (xy 246.38 144.78) (xy 228.6 144.78))
    (stroke (width 0) (type default))
  )
  (wire (pts (xy 199.39 196.85) (xy 196.85 196.85))
    (stroke (width 0) (type default))
  )
  (wire (pts (xy 118.11 100.33) (xy 118.11 102.87))
    (stroke (width 0) (type default))
  )
  (wire (pts (xy 293.37 130.81) (xy 302.26 130.81))
    (stroke (width 0) (type default))
  )
  (wire (pts (xy 110.49 102.87) (xy 110.49 104.14))
    (stroke (width 0) (type default))
  )
  (wire (pts (xy 321.31 149.86) (xy 321.31 158.75))
    (stroke (width 0) (type default))
  )
  (wire (pts (xy 302.26 85.09) (xy 308.61 85.09))
    (stroke (width 0) (type default))
  )
  (wire (pts (xy 92.71 196.85) (xy 92.71 209.55))
    (stroke (width 0) (type default))
  )
  (wire (pts (xy 231.14 161.29) (xy 228.6 161.29))
    (stroke (width 0) (type default))
  )
  (wire (pts (xy 373.38 132.08) (xy 378.46 132.08))
    (stroke (width 0) (type default))
  )
  (wire (pts (xy 196.85 194.31) (xy 186.69 194.31))
    (stroke (width 0) (type default))
  )
  (wire (pts (xy 257.81 85.09) (xy 264.16 85.09))
    (stroke (width 0) (type default))
  )
  (wire (pts (xy 295.91 85.09) (xy 295.91 88.9))
    (stroke (width 0) (type default))
  )
  (wire (pts (xy 83.82 186.69) (xy 83.82 191.77))
    (stroke (width 0) (type default))
  )
  (wire (pts (xy 287.02 106.68) (xy 287.02 107.95))
    (stroke (width 0) (type default))
  )
  (wire (pts (xy 111.76 196.85) (xy 111.76 204.47))
    (stroke (width 0) (type default))
  )
  (wire (pts (xy 287.02 137.16) (xy 287.02 140.97))
    (stroke (width 0) (type default))
  )
  (wire (pts (xy 163.83 148.59) (xy 184.15 148.59))
    (stroke (width 0) (type default))
  )
  (wire (pts (xy 118.11 92.71) (xy 118.11 95.25))
    (stroke (width 0) (type default))
  )
  (wire (pts (xy 246.38 132.08) (xy 228.6 132.08))
    (stroke (width 0) (type default))
  )
  (wire (pts (xy 125.73 102.87) (xy 133.35 102.87))
    (stroke (width 0) (type default))
  )
  (wire (pts (xy 256.54 115.57) (xy 256.54 107.95))
    (stroke (width 0) (type default))
  )
  (wire (pts (xy 184.15 156.21) (xy 163.83 156.21))
    (stroke (width 0) (type default))
  )
  (wire (pts (xy 264.16 85.09) (xy 264.16 88.9))
    (stroke (width 0) (type default))
  )
  (wire (pts (xy 257.81 93.98) (xy 257.81 97.79))
    (stroke (width 0) (type default))
  )
  (wire (pts (xy 111.76 186.69) (xy 120.65 186.69))
    (stroke (width 0) (type default))
  )
  (wire (pts (xy 140.97 228.6) (xy 40.64 228.6))
    (stroke (width 0) (type default))
  )
  (wire (pts (xy 334.01 139.7) (xy 355.6 139.7))
    (stroke (width 0) (type default))
  )
  (wire (pts (xy 349.25 157.48) (xy 355.6 157.48))
    (stroke (width 0) (type default))
  )
  (wire (pts (xy 321.31 163.83) (xy 321.31 166.37))
    (stroke (width 0) (type default))
  )
  (wire (pts (xy 256.54 130.81) (xy 279.4 130.81))
    (stroke (width 0) (type default))
  )
  (wire (pts (xy 139.7 115.57) (xy 139.7 118.11))
    (stroke (width 0) (type default))
  )
  (wire (pts (xy 58.42 220.98) (xy 132.08 220.98))
    (stroke (width 0) (type default))
  )
  (wire (pts (xy 196.85 194.31) (xy 199.39 194.31))
    (stroke (width 0) (type default))
  )
  (wire (pts (xy 274.32 119.38) (xy 267.97 119.38))
    (stroke (width 0) (type default))
  )
  (wire (pts (xy 383.54 140.97) (xy 393.7 140.97))
    (stroke (width 0) (type default))
  )
  (wire (pts (xy 58.42 186.69) (xy 49.53 186.69))
    (stroke (width 0) (type default))
  )
  (wire (pts (xy 116.84 132.08) (xy 116.84 133.35))
    (stroke (width 0) (type default))
  )
  (wire (pts (xy 256.54 107.95) (xy 267.97 107.95))
    (stroke (width 0) (type default))
  )
  (wire (pts (xy 184.15 119.38) (xy 147.32 119.38))
    (stroke (width 0) (type default))
  )
  (wire (pts (xy 111.76 186.69) (xy 102.87 186.69))
    (stroke (width 0) (type default))
  )
  (wire (pts (xy 280.67 107.95) (xy 280.67 110.49))
    (stroke (width 0) (type default))
  )
  (wire (pts (xy 118.11 92.71) (xy 125.73 92.71))
    (stroke (width 0) (type default))
  )
  (wire (pts (xy 283.21 97.79) (xy 289.56 97.79))
    (stroke (width 0) (type default))
  )
  (wire (pts (xy 113.03 115.57) (xy 125.73 115.57))
    (stroke (width 0) (type default))
  )
  (wire (pts (xy 334.01 133.35) (xy 355.6 133.35))
    (stroke (width 0) (type default))
  )
  (wire (pts (xy 184.15 144.78) (xy 163.83 144.78))
    (stroke (width 0) (type default))
  )
  (wire (pts (xy 274.32 119.38) (xy 280.67 119.38))
    (stroke (width 0) (type default))
  )
  (wire (pts (xy 246.38 138.43) (xy 228.6 138.43))
    (stroke (width 0) (type default))
  )
  (wire (pts (xy 125.73 100.33) (xy 125.73 102.87))
    (stroke (width 0) (type default))
  )
  (wire (pts (xy 283.21 93.98) (xy 283.21 97.79))
    (stroke (width 0) (type default))
  )
  (wire (pts (xy 228.6 171.45) (xy 231.14 171.45))
    (stroke (width 0) (type default))
  )
  (wire (pts (xy 83.82 186.69) (xy 74.93 186.69))
    (stroke (width 0) (type default))
  )
  (wire (pts (xy 139.7 115.57) (xy 184.15 115.57))
    (stroke (width 0) (type default))
  )
  (wire (pts (xy 274.32 115.57) (xy 274.32 119.38))
    (stroke (width 0) (type default))
  )
  (wire (pts (xy 40.64 196.85) (xy 40.64 228.6))
    (stroke (width 0) (type default))
  )
  (wire (pts (xy 163.83 153.67) (xy 184.15 153.67))
    (stroke (width 0) (type default))
  )
  (wire (pts (xy 270.51 93.98) (xy 270.51 97.79))
    (stroke (width 0) (type default))
  )
  (wire (pts (xy 120.65 186.69) (xy 120.65 191.77))
    (stroke (width 0) (type default))
  )
  (wire (pts (xy 228.6 156.21) (xy 248.92 156.21))
    (stroke (width 0) (type default))
  )
  (wire (pts (xy 111.76 186.69) (xy 111.76 191.77))
    (stroke (width 0) (type default))
  )
  (wire (pts (xy 163.83 125.73) (xy 184.15 125.73))
    (stroke (width 0) (type default))
  )
  (wire (pts (xy 330.2 152.4) (xy 355.6 152.4))
    (stroke (width 0) (type default))
  )
  (wire (pts (xy 276.86 97.79) (xy 283.21 97.79))
    (stroke (width 0) (type default))
  )
  (wire (pts (xy 133.35 102.87) (xy 140.97 102.87))
    (stroke (width 0) (type default))
  )
  (wire (pts (xy 295.91 97.79) (xy 302.26 97.79))
    (stroke (width 0) (type default))
  )
  (wire (pts (xy 289.56 97.79) (xy 295.91 97.79))
    (stroke (width 0) (type default))
  )
  (wire (pts (xy 66.04 186.69) (xy 58.42 186.69))
    (stroke (width 0) (type default))
  )
  (wire (pts (xy 340.36 154.94) (xy 355.6 154.94))
    (stroke (width 0) (type default))
  )
  (wire (pts (xy 264.16 93.98) (xy 264.16 97.79))
    (stroke (width 0) (type default))
  )
  (wire (pts (xy 110.49 92.71) (xy 101.6 92.71))
    (stroke (width 0) (type default))
  )
  (wire (pts (xy 383.54 128.27) (xy 373.38 128.27))
    (stroke (width 0) (type default))
  )
  (wire (pts (xy 163.83 142.24) (xy 184.15 142.24))
    (stroke (width 0) (type default))
  )
  (wire (pts (xy 186.69 201.93) (xy 186.69 200.66))
    (stroke (width 0) (type default))
  )
  (wire (pts (xy 289.56 85.09) (xy 283.21 85.09))
    (stroke (width 0) (type default))
  )
  (wire (pts (xy 132.08 204.47) (xy 111.76 204.47))
    (stroke (width 0) (type default))
  )
  (wire (pts (xy 58.42 186.69) (xy 58.42 191.77))
    (stroke (width 0) (type default))
  )
  (wire (pts (xy 133.35 100.33) (xy 133.35 102.87))
    (stroke (width 0) (type default))
  )
  (wire (pts (xy 383.54 137.16) (xy 373.38 137.16))
    (stroke (width 0) (type default))
  )
  (wire (pts (xy 283.21 85.09) (xy 276.86 85.09))
    (stroke (width 0) (type default))
  )
  (wire (pts (xy 125.73 92.71) (xy 125.73 95.25))
    (stroke (width 0) (type default))
  )
  (wire (pts (xy 280.67 107.95) (xy 287.02 107.95))
    (stroke (width 0) (type default))
  )
  (wire (pts (xy 279.4 132.08) (xy 279.4 130.81))
    (stroke (width 0) (type default))
  )
  (wire (pts (xy 133.35 115.57) (xy 133.35 118.11))
    (stroke (width 0) (type default))
  )
  (wire (pts (xy 66.04 186.69) (xy 66.04 191.77))
    (stroke (width 0) (type default))
  )
  (wire (pts (xy 276.86 93.98) (xy 276.86 97.79))
    (stroke (width 0) (type default))
  )
  (wire (pts (xy 92.71 186.69) (xy 92.71 191.77))
    (stroke (width 0) (type default))
  )
  (wire (pts (xy 184.15 139.7) (xy 163.83 139.7))
    (stroke (width 0) (type default))
  )
  (wire (pts (xy 287.02 140.97) (xy 293.37 140.97))
    (stroke (width 0) (type default))
  )
  (wire (pts (xy 120.65 186.69) (xy 124.46 186.69))
    (stroke (width 0) (type default))
  )
  (wire (pts (xy 287.02 119.38) (xy 287.02 120.65))
    (stroke (width 0) (type default))
  )
  (wire (pts (xy 267.97 107.95) (xy 267.97 110.49))
    (stroke (width 0) (type default))
  )
  (wire (pts (xy 118.11 102.87) (xy 125.73 102.87))
    (stroke (width 0) (type default))
  )
  (wire (pts (xy 287.02 107.95) (xy 299.72 107.95))
    (stroke (width 0) (type default))
  )
  (wire (pts (xy 330.2 152.4) (xy 330.2 158.75))
    (stroke (width 0) (type default))
  )
  (wire (pts (xy 163.83 137.16) (xy 184.15 137.16))
    (stroke (width 0) (type default))
  )
  (wire (pts (xy 289.56 93.98) (xy 289.56 97.79))
    (stroke (width 0) (type default))
  )
  (wire (pts (xy 83.82 196.85) (xy 83.82 212.09))
    (stroke (width 0) (type default))
  )
  (wire (pts (xy 184.15 128.27) (xy 163.83 128.27))
    (stroke (width 0) (type default))
  )
  (wire (pts (xy 124.46 186.69) (xy 124.46 191.77))
    (stroke (width 0) (type default))
  )
  (wire (pts (xy 349.25 163.83) (xy 349.25 166.37))
    (stroke (width 0) (type default))
  )
  (wire (pts (xy 125.73 125.73) (xy 133.35 125.73))
    (stroke (width 0) (type default))
  )
  (wire (pts (xy 302.26 93.98) (xy 302.26 97.79))
    (stroke (width 0) (type default))
  )
  (wire (pts (xy 184.15 168.91) (xy 172.72 168.91))
    (stroke (width 0) (type default))
  )
  (wire (pts (xy 133.35 115.57) (xy 139.7 115.57))
    (stroke (width 0) (type default))
  )
  (wire (pts (xy 125.73 115.57) (xy 125.73 118.11))
    (stroke (width 0) (type default))
  )
  (wire (pts (xy 274.32 107.95) (xy 274.32 110.49))
    (stroke (width 0) (type default))
  )
  (wire (pts (xy 238.76 111.76) (xy 238.76 85.09))
    (stroke (width 0) (type default))
  )
  (wire (pts (xy 116.84 138.43) (xy 116.84 139.7))
    (stroke (width 0) (type default))
  )
  (wire (pts (xy 264.16 97.79) (xy 270.51 97.79))
    (stroke (width 0) (type default))
  )
  (wire (pts (xy 218.44 194.31) (xy 228.6 194.31))
    (stroke (width 0) (type default))
  )
  (wire (pts (xy 349.25 158.75) (xy 349.25 157.48))
    (stroke (width 0) (type default))
  )
  (wire (pts (xy 267.97 107.95) (xy 274.32 107.95))
    (stroke (width 0) (type default))
  )
  (wire (pts (xy 231.14 171.45) (xy 231.14 175.26))
    (stroke (width 0) (type default))
  )
  (wire (pts (xy 184.15 151.13) (xy 163.83 151.13))
    (stroke (width 0) (type default))
  )
  (wire (pts (xy 228.6 115.57) (xy 256.54 115.57))
    (stroke (width 0) (type default))
  )
  (wire (pts (xy 74.93 186.69) (xy 74.93 191.77))
    (stroke (width 0) (type default))
  )
  (wire (pts (xy 308.61 85.09) (xy 311.15 85.09))
    (stroke (width 0) (type default))
  )
  (wire (pts (xy 133.35 92.71) (xy 133.35 95.25))
    (stroke (width 0) (type default))
  )
  (wire (pts (xy 246.38 140.97) (xy 228.6 140.97))
    (stroke (width 0) (type default))
  )
  (wire (pts (xy 132.08 201.93) (xy 120.65 201.93))
    (stroke (width 0) (type default))
  )
  (wire (pts (xy 140.97 92.71) (xy 162.56 92.71))
    (stroke (width 0) (type default))
  )
  (wire (pts (xy 125.73 115.57) (xy 133.35 115.57))
    (stroke (width 0) (type default))
  )
  (wire (pts (xy 334.01 124.46) (xy 355.6 124.46))
    (stroke (width 0) (type default))
  )
  (wire (pts (xy 293.37 140.97) (xy 293.37 142.24))
    (stroke (width 0) (type default))
  )
  (wire (pts (xy 270.51 85.09) (xy 270.51 88.9))
    (stroke (width 0) (type default))
  )
  (wire (pts (xy 125.73 125.73) (xy 125.73 127))
    (stroke (width 0) (type default))
  )
  (wire (pts (xy 280.67 119.38) (xy 287.02 119.38))
    (stroke (width 0) (type default))
  )
  (wire (pts (xy 124.46 196.85) (xy 124.46 199.39))
    (stroke (width 0) (type default))
  )
  (wire (pts (xy 40.64 186.69) (xy 31.75 186.69))
    (stroke (width 0) (type default))
  )
  (wire (pts (xy 163.83 132.08) (xy 184.15 132.08))
    (stroke (width 0) (type default))
  )
  (wire (pts (xy 132.08 218.44) (xy 66.04 218.44))
    (stroke (width 0) (type default))
  )
  (wire (pts (xy 199.39 199.39) (xy 196.85 199.39))
    (stroke (width 0) (type default))
  )
  (wire (pts (xy 276.86 85.09) (xy 276.86 88.9))
    (stroke (width 0) (type default))
  )
  (wire (pts (xy 276.86 85.09) (xy 270.51 85.09))
    (stroke (width 0) (type default))
  )
  (wire (pts (xy 102.87 196.85) (xy 102.87 207.01))
    (stroke (width 0) (type default))
  )
  (wire (pts (xy 270.51 85.09) (xy 264.16 85.09))
    (stroke (width 0) (type default))
  )
  (wire (pts (xy 257.81 97.79) (xy 264.16 97.79))
    (stroke (width 0) (type default))
  )
  (wire (pts (xy 163.83 158.75) (xy 184.15 158.75))
    (stroke (width 0) (type default))
  )
  (wire (pts (xy 340.36 158.75) (xy 340.36 154.94))
    (stroke (width 0) (type default))
  )
  (wire (pts (xy 340.36 163.83) (xy 340.36 166.37))
    (stroke (width 0) (type default))
  )
  (wire (pts (xy 125.73 114.3) (xy 125.73 115.57))
    (stroke (width 0) (type default))
  )
  (wire (pts (xy 74.93 186.69) (xy 66.04 186.69))
    (stroke (width 0) (type default))
  )
  (wire (pts (xy 373.38 154.94) (xy 374.65 154.94))
    (stroke (width 0) (type default))
  )
  (wire (pts (xy 373.38 140.97) (xy 378.46 140.97))
    (stroke (width 0) (type default))
  )
  (wire (pts (xy 257.81 85.09) (xy 257.81 88.9))
    (stroke (width 0) (type default))
  )
  (wire (pts (xy 279.4 130.81) (xy 287.02 130.81))
    (stroke (width 0) (type default))
  )
  (wire (pts (xy 279.4 137.16) (xy 279.4 140.97))
    (stroke (width 0) (type default))
  )
  (wire (pts (xy 287.02 132.08) (xy 287.02 130.81))
    (stroke (width 0) (type default))
  )
  (wire (pts (xy 355.6 149.86) (xy 321.31 149.86))
    (stroke (width 0) (type default))
  )
  (wire (pts (xy 293.37 137.16) (xy 293.37 140.97))
    (stroke (width 0) (type default))
  )
  (wire (pts (xy 92.71 209.55) (xy 132.08 209.55))
    (stroke (width 0) (type default))
  )
  (wire (pts (xy 196.85 196.85) (xy 196.85 194.31))
    (stroke (width 0) (type default))
  )
  (wire (pts (xy 102.87 186.69) (xy 102.87 191.77))
    (stroke (width 0) (type default))
  )
  (wire (pts (xy 374.65 154.94) (xy 374.65 166.37))
    (stroke (width 0) (type default))
  )
  (wire (pts (xy 92.71 186.69) (xy 83.82 186.69))
    (stroke (width 0) (type default))
  )
  (wire (pts (xy 140.97 92.71) (xy 140.97 95.25))
    (stroke (width 0) (type default))
  )
  (wire (pts (xy 280.67 115.57) (xy 280.67 119.38))
    (stroke (width 0) (type default))
  )
  (wire (pts (xy 246.38 147.32) (xy 228.6 147.32))
    (stroke (width 0) (type default))
  )
  (wire (pts (xy 49.53 186.69) (xy 49.53 191.77))
    (stroke (width 0) (type default))
  )

  (text "RJ45 connector" (at 338.455 112.395 0)
    (effects (font (size 2.0066 2.0066)) (justify left bottom))
  )
  (text "Pull up resistors" (at 95.25 180.975 0)
    (effects (font (size 2.0066 2.0066)) (justify right bottom))
  )

  (label "ETH1_P" (at 334.01 124.46 0) (fields_autoplaced)
    (effects (font (size 1.27 1.27)) (justify left bottom))
  )
  (label "ETH4_P" (at 334.01 143.51 0) (fields_autoplaced)
    (effects (font (size 1.27 1.27)) (justify left bottom))
  )
  (label "ETH4_P" (at 246.38 144.78 180) (fields_autoplaced)
    (effects (font (size 1.27 1.27)) (justify right bottom))
  )
  (label "AVDDL" (at 256.54 107.95 0) (fields_autoplaced)
    (effects (font (size 1.27 1.27)) (justify left bottom))
  )
  (label "ETH_LED2" (at 393.7 140.97 180) (fields_autoplaced)
    (effects (font (size 1.27 1.27)) (justify right bottom))
  )
  (label "ETH4_N" (at 246.38 147.32 180) (fields_autoplaced)
    (effects (font (size 1.27 1.27)) (justify right bottom))
  )
  (label "ETH2_N" (at 246.38 134.62 180) (fields_autoplaced)
    (effects (font (size 1.27 1.27)) (justify right bottom))
  )
  (label "ETH4_N" (at 334.01 146.05 0) (fields_autoplaced)
    (effects (font (size 1.27 1.27)) (justify left bottom))
  )
  (label "ETH2_P" (at 246.38 132.08 180) (fields_autoplaced)
    (effects (font (size 1.27 1.27)) (justify right bottom))
  )
  (label "ETH1_P" (at 246.38 125.73 180) (fields_autoplaced)
    (effects (font (size 1.27 1.27)) (justify right bottom))
  )
  (label "ETH2_N" (at 334.01 133.35 0) (fields_autoplaced)
    (effects (font (size 1.27 1.27)) (justify left bottom))
  )
  (label "PHY_CLK" (at 172.72 168.91 0) (fields_autoplaced)
    (effects (font (size 1.27 1.27)) (justify left bottom))
  )
  (label "ETH1_N" (at 246.38 128.27 180) (fields_autoplaced)
    (effects (font (size 1.27 1.27)) (justify right bottom))
  )
  (label "ETH1_N" (at 334.01 127 0) (fields_autoplaced)
    (effects (font (size 1.27 1.27)) (justify left bottom))
  )
  (label "ETH_LED2" (at 248.92 156.21 180) (fields_autoplaced)
    (effects (font (size 1.27 1.27)) (justify right bottom))
  )
  (label "ETH_LED1" (at 248.92 153.67 180) (fields_autoplaced)
    (effects (font (size 1.27 1.27)) (justify right bottom))
  )
  (label "ETH3_N" (at 246.38 140.97 180) (fields_autoplaced)
    (effects (font (size 1.27 1.27)) (justify right bottom))
  )
  (label "ETH3_N" (at 334.01 139.7 0) (fields_autoplaced)
    (effects (font (size 1.27 1.27)) (justify left bottom))
  )
  (label "ETH2_P" (at 334.01 130.81 0) (fields_autoplaced)
    (effects (font (size 1.27 1.27)) (justify left bottom))
  )
  (label "ETH3_P" (at 334.01 137.16 0) (fields_autoplaced)
    (effects (font (size 1.27 1.27)) (justify left bottom))
  )
  (label "ETH_LED2" (at 140.97 228.6 180) (fields_autoplaced)
    (effects (font (size 1.27 1.27)) (justify right bottom))
  )
  (label "ETH_LED1" (at 393.7 132.08 180) (fields_autoplaced)
    (effects (font (size 1.27 1.27)) (justify right bottom))
  )
  (label "ETH_LED1" (at 140.97 224.79 180) (fields_autoplaced)
    (effects (font (size 1.27 1.27)) (justify right bottom))
  )
  (label "PHY_CLK" (at 228.6 194.31 180) (fields_autoplaced)
    (effects (font (size 1.27 1.27)) (justify right bottom))
  )
  (label "ETH3_P" (at 246.38 138.43 180) (fields_autoplaced)
    (effects (font (size 1.27 1.27)) (justify right bottom))
  )
  (label "AVDDL_PLL" (at 256.54 130.81 0) (fields_autoplaced)
    (effects (font (size 1.27 1.27)) (justify left bottom))
  )
  (label "AVDDH" (at 162.56 115.57 180) (fields_autoplaced)
    (effects (font (size 1.27 1.27)) (justify right bottom))
  )

  (global_label "ETH_INT_N" (shape output) (at 163.83 121.92 180) (fields_autoplaced)
    (effects (font (size 1.27 1.27)) (justify right))
    (property "Intersheetrefs" "${INTERSHEET_REFS}" (at 52.705 -31.75 0)
      (effects (font (size 1.27 1.27)) hide)
    )
  )
  (global_label "RGMII_TX_EN" (shape input) (at 163.83 132.08 180) (fields_autoplaced)
    (effects (font (size 1.27 1.27)) (justify right))
    (property "Intersheetrefs" "${INTERSHEET_REFS}" (at 52.07 19.05 0)
      (effects (font (size 1.27 1.27)) hide)
    )
  )
  (global_label "RGMII_RXD1" (shape output) (at 163.83 153.67 180) (fields_autoplaced)
    (effects (font (size 1.27 1.27)) (justify right))
    (property "Intersheetrefs" "${INTERSHEET_REFS}" (at 52.07 17.78 0)
      (effects (font (size 1.27 1.27)) hide)
    )
  )
  (global_label "RGMII_RX_DV" (shape passive) (at 132.08 209.55 0) (fields_autoplaced)
    (effects (font (size 1.27 1.27)) (justify left))
    (property "Intersheetrefs" "${INTERSHEET_REFS}" (at 177.8 -44.45 0)
      (effects (font (size 1.27 1.27)) hide)
    )
  )
  (global_label "VCC1V2" (shape input) (at 309.88 130.81 0) (fields_autoplaced)
    (effects (font (size 1.27 1.27)) (justify left))
    (property "Intersheetrefs" "${INTERSHEET_REFS}" (at 74.295 53.34 0)
      (effects (font (size 1.27 1.27)) hide)
    )
  )
  (global_label "RGMII_RXD3" (shape output) (at 163.83 158.75 180) (fields_autoplaced)
    (effects (font (size 1.27 1.27)) (justify right))
    (property "Intersheetrefs" "${INTERSHEET_REFS}" (at 52.07 17.78 0)
      (effects (font (size 1.27 1.27)) hide)
    )
  )
  (global_label "RGMII_TXD2" (shape input) (at 163.83 139.7 180) (fields_autoplaced)
    (effects (font (size 1.27 1.27)) (justify right))
    (property "Intersheetrefs" "${INTERSHEET_REFS}" (at 52.07 19.05 0)
      (effects (font (size 1.27 1.27)) hide)
    )
  )
  (global_label "VCC3V3" (shape input) (at 383.54 137.16 0) (fields_autoplaced)
    (effects (font (size 1.27 1.27)) (justify left))
    (property "Intersheetrefs" "${INTERSHEET_REFS}" (at 393.0072 137.16 0)
      (effects (font (size 1.27 1.27)) (justify left) hide)
    )
  )
  (global_label "RGMII_RX_DV" (shape output) (at 163.83 148.59 180) (fields_autoplaced)
    (effects (font (size 1.27 1.27)) (justify right))
    (property "Intersheetrefs" "${INTERSHEET_REFS}" (at 52.07 17.78 0)
      (effects (font (size 1.27 1.27)) hide)
    )
  )
  (global_label "RGMII_TX_CLK" (shape input) (at 163.83 144.78 180) (fields_autoplaced)
    (effects (font (size 1.27 1.27)) (justify right))
    (property "Intersheetrefs" "${INTERSHEET_REFS}" (at 52.07 19.05 0)
      (effects (font (size 1.27 1.27)) hide)
    )
  )
  (global_label "RGMII_RXD0" (shape output) (at 163.83 151.13 180) (fields_autoplaced)
    (effects (font (size 1.27 1.27)) (justify right))
    (property "Intersheetrefs" "${INTERSHEET_REFS}" (at 52.07 17.78 0)
      (effects (font (size 1.27 1.27)) hide)
    )
  )
  (global_label "VCC3V3" (shape input) (at 101.6 92.71 180) (fields_autoplaced)
    (effects (font (size 1.27 1.27)) (justify right))
    (property "Intersheetrefs" "${INTERSHEET_REFS}" (at 10.795 15.24 0)
      (effects (font (size 1.27 1.27)) hide)
    )
  )
  (global_label "RGMII_TXD0" (shape input) (at 163.83 134.62 180) (fields_autoplaced)
    (effects (font (size 1.27 1.27)) (justify right))
    (property "Intersheetrefs" "${INTERSHEET_REFS}" (at 52.07 19.05 0)
      (effects (font (size 1.27 1.27)) hide)
    )
  )
  (global_label "RGMII_REF_CLK" (shape passive) (at 132.08 214.63 0) (fields_autoplaced)
    (effects (font (size 1.27 1.27)) (justify left))
    (property "Intersheetrefs" "${INTERSHEET_REFS}" (at 177.8 -44.45 0)
      (effects (font (size 1.27 1.27)) hide)
    )
  )
  (global_label "ETH_MDIO" (shape bidirectional) (at 163.83 128.27 180) (fields_autoplaced)
    (effects (font (size 1.27 1.27)) (justify right))
    (property "Intersheetrefs" "${INTERSHEET_REFS}" (at 52.07 20.32 0)
      (effects (font (size 1.27 1.27)) hide)
    )
  )
  (global_label "RGMII_RXD3" (shape passive) (at 132.08 207.01 0) (fields_autoplaced)
    (effects (font (size 1.27 1.27)) (justify left))
    (property "Intersheetrefs" "${INTERSHEET_REFS}" (at 177.8 -44.45 0)
      (effects (font (size 1.27 1.27)) hide)
    )
  )
  (global_label "VCC3V3" (shape input) (at 186.69 193.04 90) (fields_autoplaced)
    (effects (font (size 1.27 1.27)) (justify left))
    (property "Intersheetrefs" "${INTERSHEET_REFS}" (at -69.215 14.605 0)
      (effects (font (size 1.27 1.27)) hide)
    )
  )
  (global_label "RGMII_TXD1" (shape input) (at 163.83 137.16 180) (fields_autoplaced)
    (effects (font (size 1.27 1.27)) (justify right))
    (property "Intersheetrefs" "${INTERSHEET_REFS}" (at 52.07 19.05 0)
      (effects (font (size 1.27 1.27)) hide)
    )
  )
  (global_label "ETH_MDC" (shape input) (at 163.83 125.73 180) (fields_autoplaced)
    (effects (font (size 1.27 1.27)) (justify right))
    (property "Intersheetrefs" "${INTERSHEET_REFS}" (at 52.07 20.32 0)
      (effects (font (size 1.27 1.27)) hide)
    )
  )
  (global_label "ETH_INT_N" (shape output) (at 132.08 220.98 0) (fields_autoplaced)
    (effects (font (size 1.27 1.27)) (justify left))
    (property "Intersheetrefs" "${INTERSHEET_REFS}" (at 178.435 -47.625 0)
      (effects (font (size 1.27 1.27)) hide)
    )
  )
  (global_label "VCC1V2" (shape input) (at 309.88 107.95 0) (fields_autoplaced)
    (effects (font (size 1.27 1.27)) (justify left))
    (property "Intersheetrefs" "${INTERSHEET_REFS}" (at 74.295 59.055 0)
      (effects (font (size 1.27 1.27)) hide)
    )
  )
  (global_label "VCC1V2" (shape input) (at 311.15 85.09 0) (fields_autoplaced)
    (effects (font (size 1.27 1.27)) (justify left))
    (property "Intersheetrefs" "${INTERSHEET_REFS}" (at 376.555 51.435 0)
      (effects (font (size 1.27 1.27)) hide)
    )
  )
  (global_label "RGMII_REF_CLK" (shape output) (at 163.83 165.1 180) (fields_autoplaced)
    (effects (font (size 1.27 1.27)) (justify right))
    (property "Intersheetrefs" "${INTERSHEET_REFS}" (at 52.705 6.35 0)
      (effects (font (size 1.27 1.27)) hide)
    )
  )
  (global_label "RGMII_TXD3" (shape input) (at 163.83 142.24 180) (fields_autoplaced)
    (effects (font (size 1.27 1.27)) (justify right))
    (property "Intersheetrefs" "${INTERSHEET_REFS}" (at 52.07 19.05 0)
      (effects (font (size 1.27 1.27)) hide)
    )
  )
  (global_label "RGMII_RXD2" (shape passive) (at 132.08 204.47 0) (fields_autoplaced)
    (effects (font (size 1.27 1.27)) (justify left))
    (property "Intersheetrefs" "${INTERSHEET_REFS}" (at 177.8 -44.45 0)
      (effects (font (size 1.27 1.27)) hide)
    )
  )
  (global_label "RGMII_RX_CLK" (shape passive) (at 132.08 212.09 0) (fields_autoplaced)
    (effects (font (size 1.27 1.27)) (justify left))
    (property "Intersheetrefs" "${INTERSHEET_REFS}" (at 177.8 -44.45 0)
      (effects (font (size 1.27 1.27)) hide)
    )
  )
  (global_label "RGMII_RXD2" (shape output) (at 163.83 156.21 180) (fields_autoplaced)
    (effects (font (size 1.27 1.27)) (justify right))
    (property "Intersheetrefs" "${INTERSHEET_REFS}" (at 52.07 17.78 0)
      (effects (font (size 1.27 1.27)) hide)
    )
  )
  (global_label "VCC3V3" (shape input) (at 31.75 186.69 180) (fields_autoplaced)
    (effects (font (size 1.27 1.27)) (justify right))
    (property "Intersheetrefs" "${INTERSHEET_REFS}" (at 164.465 -26.67 0)
      (effects (font (size 1.27 1.27)) hide)
    )
  )
  (global_label "RGMII_RXD1" (shape passive) (at 132.08 201.93 0) (fields_autoplaced)
    (effects (font (size 1.27 1.27)) (justify left))
    (property "Intersheetrefs" "${INTERSHEET_REFS}" (at 177.8 -44.45 0)
      (effects (font (size 1.27 1.27)) hide)
    )
  )
  (global_label "VCC3V3" (shape input) (at 116.84 132.08 90) (fields_autoplaced)
    (effects (font (size 1.27 1.27)) (justify left))
    (property "Intersheetrefs" "${INTERSHEET_REFS}" (at 31.75 -19.05 0)
      (effects (font (size 1.27 1.27)) hide)
    )
  )
  (global_label "RGMII_RXD0" (shape passive) (at 132.08 199.39 0) (fields_autoplaced)
    (effects (font (size 1.27 1.27)) (justify left))
    (property "Intersheetrefs" "${INTERSHEET_REFS}" (at 177.8 -44.45 0)
      (effects (font (size 1.27 1.27)) hide)
    )
  )
  (global_label "RGMII_TX_EN" (shape input) (at 163.83 132.08 180) (fields_autoplaced)
    (effects (font (size 1.27 1.27)) (justify right))
    (property "Intersheetrefs" "${INTERSHEET_REFS}" (at 52.07 19.05 0)
      (effects (font (size 1.27 1.27)) hide)
    )
  )
  (global_label "ETH_~{RESET}" (shape input) (at 111.76 139.7 180) (fields_autoplaced)
    (effects (font (size 1.27 1.27)) (justify right))
    (property "Intersheetrefs" "${INTERSHEET_REFS}" (at 31.75 -23.495 0)
      (effects (font (size 1.27 1.27)) hide)
    )
  )
  (global_label "VCC3V3" (shape input) (at 383.54 128.27 0) (fields_autoplaced)
    (effects (font (size 1.27 1.27)) (justify left))
    (property "Intersheetrefs" "${INTERSHEET_REFS}" (at 393.0072 128.27 0)
      (effects (font (size 1.27 1.27)) (justify left) hide)
    )
  )
  (global_label "VCC3V3" (shape input) (at 101.6 115.57 180) (fields_autoplaced)
    (effects (font (size 1.27 1.27)) (justify right))
    (property "Intersheetrefs" "${INTERSHEET_REFS}" (at 14.605 59.69 0)
      (effects (font (size 1.27 1.27)) hide)
    )
  )
  (global_label "RGMII_RX_CLK" (shape output) (at 163.83 161.29 180) (fields_autoplaced)
    (effects (font (size 1.27 1.27)) (justify right))
    (property "Intersheetrefs" "${INTERSHEET_REFS}" (at 52.07 17.78 0)
      (effects (font (size 1.27 1.27)) hide)
    )
  )
  (global_label "ETH_MDIO" (shape passive) (at 132.08 218.44 0) (fields_autoplaced)
    (effects (font (size 1.27 1.27)) (justify left))
    (property "Intersheetrefs" "${INTERSHEET_REFS}" (at 178.435 -46.99 0)
      (effects (font (size 1.27 1.27)) hide)
    )
  )

  (symbol (lib_id "antmicroResistors0402:R_2k2_0402") (at 66.04 191.77 90) (mirror x) (unit 1)
    (in_bom yes) (on_board yes) (dnp no)
    (property "Reference" "R9" (at 64.77 193.04 90)
      (effects (font (size 1.524 1.524)) (justify left))
    )
    (property "Value" "R_2k2_0402" (at 69.85 191.77 0)
      (effects (font (size 1.524 1.524)) hide)
    )
    (property "Footprint" "antmicro-footprints:R_0402_1005Metric" (at 60.96 196.85 0)
      (effects (font (size 1.524 1.524)) (justify left) hide)
    )
    (property "Datasheet" "https://www.bourns.com/docs/product-datasheets/cr.pdf" (at 66.04 191.77 0)
      (effects (font (size 1.27 1.27)) hide)
    )
    (property "Manufacturer" "Bourns" (at 55.88 196.85 0)
      (effects (font (size 1.524 1.524)) (justify left) hide)
    )
    (property "MPN" "CR0402-FX-2201GLF" (at 58.42 196.85 0)
      (effects (font (size 1.524 1.524)) (justify left) hide)
    )
    (property "Val" "2k2" (at 64.77 195.58 90)
      (effects (font (size 1.27 1.27)) (justify left))
    )
    (property "License" "Apache-2.0" (at 91.44 212.09 0)
      (effects (font (size 1.27 1.27) (thickness 0.15)) (justify left bottom) hide)
    )
    (property "Author" "Antmicro" (at 93.98 212.09 0)
      (effects (font (size 1.27 1.27) (thickness 0.15)) (justify left bottom) hide)
    )
    (property "Tolerance" "1%" (at 76.2 212.09 0)
      (effects (font (size 1.27 1.27)) (justify left bottom) hide)
    )
    (property "Public" "False" (at 96.52 212.09 0)
      (effects (font (size 1.27 1.27)) (justify left bottom) hide)
    )
    (pin "1")
    (pin "2")
    (instances
      (project "ecp5-dc-scm"
        (path ""
          (reference "R9") (unit 1)
        )
      )
    )
  )

  (symbol (lib_id "antmicroResistors0402:R_1k_0402") (at 378.46 132.08 0) (unit 1)
    (in_bom yes) (on_board yes) (dnp no)
    (property "Reference" "R16" (at 381 129.54 0)
      (effects (font (size 1.524 1.524)))
    )
    (property "Value" "R_1k_0402" (at 378.46 135.89 0)
      (effects (font (size 1.524 1.524)) hide)
    )
    (property "Footprint" "antmicro-footprints:R_0402_1005Metric" (at 383.54 127 0)
      (effects (font (size 1.524 1.524)) (justify left) hide)
    )
    (property "Datasheet" "https://www.bourns.com/docs/product-datasheets/cr.pdf" (at 378.46 132.08 0)
      (effects (font (size 1.27 1.27)) hide)
    )
    (property "Manufacturer" "Bourns" (at 383.54 121.92 0)
      (effects (font (size 1.524 1.524)) (justify left) hide)
    )
    (property "MPN" "CR0402-FX-1001GLF" (at 383.54 124.46 0)
      (effects (font (size 1.524 1.524)) (justify left) hide)
    )
    (property "Val" "1k" (at 381 134.62 0)
      (effects (font (size 1.27 1.27)))
    )
    (property "License" "Apache-2.0" (at 398.78 157.48 0)
      (effects (font (size 1.27 1.27) (thickness 0.15)) (justify left bottom) hide)
    )
    (property "Author" "Antmicro" (at 398.78 160.02 0)
      (effects (font (size 1.27 1.27) (thickness 0.15)) (justify left bottom) hide)
    )
    (property "Tolerance" "1%" (at 398.78 142.24 0)
      (effects (font (size 1.27 1.27)) (justify left bottom) hide)
    )
    (property "Public" "False" (at 398.78 162.56 0)
      (effects (font (size 1.27 1.27)) (justify left bottom) hide)
    )
    (pin "1")
    (pin "2")
    (instances
      (project "ecp5-dc-scm"
        (path ""
          (reference "R16") (unit 1)
        )
      )
    )
  )

  (symbol (lib_id "antmicroResistors0402:R_1k_0402") (at 378.46 140.97 0) (unit 1)
    (in_bom yes) (on_board yes) (dnp no)
    (property "Reference" "R15" (at 381 138.43 0)
      (effects (font (size 1.524 1.524)))
    )
    (property "Value" "R_1k_0402" (at 378.46 144.78 0)
      (effects (font (size 1.524 1.524)) hide)
    )
    (property "Footprint" "antmicro-footprints:R_0402_1005Metric" (at 383.54 135.89 0)
      (effects (font (size 1.524 1.524)) (justify left) hide)
    )
    (property "Datasheet" "https://www.bourns.com/docs/product-datasheets/cr.pdf" (at 378.46 140.97 0)
      (effects (font (size 1.27 1.27)) hide)
    )
    (property "Manufacturer" "Bourns" (at 383.54 130.81 0)
      (effects (font (size 1.524 1.524)) (justify left) hide)
    )
    (property "MPN" "CR0402-FX-1001GLF" (at 383.54 133.35 0)
      (effects (font (size 1.524 1.524)) (justify left) hide)
    )
    (property "Val" "1k" (at 381 143.51 0)
      (effects (font (size 1.27 1.27)))
    )
    (property "License" "Apache-2.0" (at 398.78 166.37 0)
      (effects (font (size 1.27 1.27) (thickness 0.15)) (justify left bottom) hide)
    )
    (property "Author" "Antmicro" (at 398.78 168.91 0)
      (effects (font (size 1.27 1.27) (thickness 0.15)) (justify left bottom) hide)
    )
    (property "Tolerance" "1%" (at 398.78 151.13 0)
      (effects (font (size 1.27 1.27)) (justify left bottom) hide)
    )
    (property "Public" "False" (at 398.78 171.45 0)
      (effects (font (size 1.27 1.27)) (justify left bottom) hide)
    )
    (pin "1")
    (pin "2")
    (instances
      (project "ecp5-dc-scm"
        (path ""
          (reference "R15") (unit 1)
        )
      )
    )
  )

  (symbol (lib_id "antmicropower:GND") (at 374.65 166.37 0) (unit 1)
    (in_bom yes) (on_board yes) (dnp no)
    (property "Reference" "#PWR09" (at 374.65 172.72 0)
      (effects (font (size 1.27 1.27)) hide)
    )
    (property "Value" "GND" (at 374.777 170.7642 0)
      (effects (font (size 1.27 1.27)))
    )
    (property "Footprint" "" (at 374.65 166.37 0)
      (effects (font (size 1.27 1.27)) hide)
    )
    (property "Datasheet" "" (at 374.65 166.37 0)
      (effects (font (size 1.27 1.27)) hide)
    )
    (property "Author" "Antmicro" (at 383.54 173.99 0)
      (effects (font (size 1.27 1.27) (thickness 0.15)) (justify left bottom) hide)
    )
    (property "License" "Apache-2.0" (at 383.54 176.53 0)
      (effects (font (size 1.27 1.27) (thickness 0.15)) (justify left bottom) hide)
    )
    (pin "1")
    (instances
      (project "ecp5-dc-scm"
        (path ""
          (reference "#PWR09") (unit 1)
        )
      )
    )
  )

  (symbol (lib_id "antmicroCapacitors0402:C_4u7_0402") (at 267.97 115.57 90) (unit 1)
    (in_bom yes) (on_board yes) (dnp no)
    (property "Reference" "C18" (at 273.05 110.49 90)
      (effects (font (size 1.524 1.524)) (justify left))
    )
    (property "Value" "C_4u7_0402" (at 271.78 115.57 0)
      (effects (font (size 1.524 1.524)) hide)
    )
    (property "Footprint" "antmicro-footprints:C_0402_1005Metric" (at 262.89 110.49 0)
      (effects (font (size 1.524 1.524)) (justify left) hide)
    )
    (property "Datasheet" "https://www.murata.com/products/productdetail?partno=GRM155R61A475MEAA%23" (at 267.97 115.57 0)
      (effects (font (size 1.27 1.27)) hide)
    )
    (property "Manufacturer" "Murata" (at 257.81 110.49 0)
      (effects (font (size 1.524 1.524)) (justify left) hide)
    )
    (property "MPN" "GRM155R61A475MEAAD" (at 260.35 110.49 0)
      (effects (font (size 1.524 1.524)) (justify left) hide)
    )
    (property "Val" "4u7" (at 271.78 115.57 90)
      (effects (font (size 1.27 1.27)) (justify left))
    )
    (property "License" "Apache-2.0" (at 290.83 95.25 0)
      (effects (font (size 1.27 1.27) (thickness 0.15)) (justify left bottom) hide)
    )
    (property "Author" "Antmicro" (at 293.37 95.25 0)
      (effects (font (size 1.27 1.27) (thickness 0.15)) (justify left bottom) hide)
    )
    (property "Voltage" "" (at 295.91 95.25 0)
      (effects (font (size 1.27 1.27)) (justify left bottom) hide)
    )
    (property "Dielectric" "" (at 298.45 95.25 0)
      (effects (font (size 1.27 1.27)) (justify left bottom) hide)
    )
    (property "Public" "False" (at 300.99 95.25 0)
      (effects (font (size 1.27 1.27)) (justify left bottom) hide)
    )
    (pin "1")
    (pin "2")
    (instances
      (project "ecp5-dc-scm"
        (path ""
          (reference "C18") (unit 1)
        )
      )
    )
  )

  (symbol (lib_id "antmicroCapacitors0402:C_470n_0402") (at 274.32 115.57 90) (unit 1)
    (in_bom yes) (on_board yes) (dnp no)
    (property "Reference" "C19" (at 274.32 110.49 90)
      (effects (font (size 1.524 1.524)) (justify right))
    )
    (property "Value" "C_470n_0402" (at 278.13 115.57 0)
      (effects (font (size 1.524 1.524)) hide)
    )
    (property "Footprint" "antmicro-footprints:C_0402_1005Metric" (at 269.24 110.49 0)
      (effects (font (size 1.524 1.524)) (justify left) hide)
    )
    (property "Datasheet" "https://product.tdk.com/en/search/capacitor/ceramic/mlcc/info?part_no=C1005X5R1E474M050BB" (at 274.32 115.57 0)
      (effects (font (size 1.27 1.27)) hide)
    )
    (property "Manufacturer" "TDK" (at 264.16 110.49 0)
      (effects (font (size 1.524 1.524)) (justify left) hide)
    )
    (property "MPN" "C1005X5R1E474M050BB" (at 266.7 110.49 0)
      (effects (font (size 1.524 1.524)) (justify left) hide)
    )
    (property "Val" "470n" (at 274.32 115.57 90)
      (effects (font (size 1.27 1.27)) (justify right))
    )
    (property "License" "Apache-2.0" (at 297.18 95.25 0)
      (effects (font (size 1.27 1.27) (thickness 0.15)) (justify left bottom) hide)
    )
    (property "Author" "Antmicro" (at 299.72 95.25 0)
      (effects (font (size 1.27 1.27) (thickness 0.15)) (justify left bottom) hide)
    )
    (property "Voltage" "" (at 302.26 95.25 0)
      (effects (font (size 1.27 1.27)) (justify left bottom) hide)
    )
    (property "Dielectric" "" (at 304.8 95.25 0)
      (effects (font (size 1.27 1.27)) (justify left bottom) hide)
    )
    (property "Public" "False" (at 307.34 95.25 0)
      (effects (font (size 1.27 1.27)) (justify left bottom) hide)
    )
    (pin "1")
    (pin "2")
    (instances
      (project "ecp5-dc-scm"
        (path ""
          (reference "C19") (unit 1)
        )
      )
    )
  )

  (symbol (lib_id "antmicroCapacitors0402:C_10n_0402") (at 280.67 115.57 90) (unit 1)
    (in_bom yes) (on_board yes) (dnp no)
    (property "Reference" "C21" (at 280.67 110.49 90)
      (effects (font (size 1.524 1.524)) (justify right))
    )
    (property "Value" "C_10n_0402" (at 284.48 115.57 0)
      (effects (font (size 1.524 1.524)) hide)
    )
    (property "Footprint" "antmicro-footprints:C_0402_1005Metric" (at 275.59 110.49 0)
      (effects (font (size 1.524 1.524)) (justify left) hide)
    )
    (property "Datasheet" "https://www.murata.com/products/productdetail?partno=GRM155R71H103KA88%23" (at 280.67 115.57 0)
      (effects (font (size 1.27 1.27)) hide)
    )
    (property "Manufacturer" "Murata" (at 270.51 110.49 0)
      (effects (font (size 1.524 1.524)) (justify left) hide)
    )
    (property "MPN" "GRM155R71H103KA88D" (at 273.05 110.49 0)
      (effects (font (size 1.524 1.524)) (justify left) hide)
    )
    (property "Val" "10n" (at 280.67 115.57 90)
      (effects (font (size 1.27 1.27)) (justify right))
    )
    (property "License" "Apache-2.0" (at 303.53 95.25 0)
      (effects (font (size 1.27 1.27) (thickness 0.15)) (justify left bottom) hide)
    )
    (property "Author" "Antmicro" (at 306.07 95.25 0)
      (effects (font (size 1.27 1.27) (thickness 0.15)) (justify left bottom) hide)
    )
    (property "Voltage" "50V" (at 308.61 95.25 0)
      (effects (font (size 1.27 1.27)) (justify left bottom) hide)
    )
    (property "Dielectric" "X7R" (at 311.15 95.25 0)
      (effects (font (size 1.27 1.27)) (justify left bottom) hide)
    )
    (property "Public" "False" (at 313.69 95.25 0)
      (effects (font (size 1.27 1.27)) (justify left bottom) hide)
    )
    (pin "1")
    (pin "2")
    (instances
      (project "ecp5-dc-scm"
        (path ""
          (reference "C21") (unit 1)
        )
      )
    )
  )

  (symbol (lib_id "antmicroCapacitors0402:C_100n_0402") (at 287.02 137.16 90) (unit 1)
    (in_bom yes) (on_board yes) (dnp no)
    (property "Reference" "C24" (at 280.67 133.35 90)
      (effects (font (size 1.524 1.524)) (justify right))
    )
    (property "Value" "C_100n_0402" (at 290.83 137.16 0)
      (effects (font (size 1.524 1.524)) hide)
    )
    (property "Footprint" "antmicro-footprints:C_0402_1005Metric" (at 281.94 132.08 0)
      (effects (font (size 1.524 1.524)) (justify left) hide)
    )
    (property "Datasheet" "https://www.murata.com/products/productdetail?partno=GRM155R61H104KE14%23" (at 287.02 137.16 0)
      (effects (font (size 1.27 1.27)) hide)
    )
    (property "Manufacturer" "Murata" (at 276.86 132.08 0)
      (effects (font (size 1.524 1.524)) (justify left) hide)
    )
    (property "MPN" "GRM155R61H104KE14D" (at 279.4 132.08 0)
      (effects (font (size 1.524 1.524)) (justify left) hide)
    )
    (property "Val" "100n" (at 281.94 137.16 90)
      (effects (font (size 1.27 1.27)) (justify right))
    )
    (property "License" "Apache-2.0" (at 309.88 116.84 0)
      (effects (font (size 1.27 1.27) (thickness 0.15)) (justify left bottom) hide)
    )
    (property "Author" "Antmicro" (at 312.42 116.84 0)
      (effects (font (size 1.27 1.27) (thickness 0.15)) (justify left bottom) hide)
    )
    (property "Voltage" "50V" (at 314.96 116.84 0)
      (effects (font (size 1.27 1.27)) (justify left bottom) hide)
    )
    (property "Dielectric" "X5R" (at 317.5 116.84 0)
      (effects (font (size 1.27 1.27)) (justify left bottom) hide)
    )
    (property "Public" "False" (at 320.04 116.84 0)
      (effects (font (size 1.27 1.27)) (justify left bottom) hide)
    )
    (pin "1")
    (pin "2")
    (instances
      (project "ecp5-dc-scm"
        (path ""
          (reference "C24") (unit 1)
        )
      )
    )
  )

  (symbol (lib_id "antmicroCapacitors0402:C_10n_0402") (at 186.69 200.66 90) (unit 1)
    (in_bom yes) (on_board yes) (dnp no) (fields_autoplaced)
    (property "Reference" "C20" (at 189.23 196.8436 90)
      (effects (font (size 1.524 1.524)) (justify right))
    )
    (property "Value" "C_10n_0402" (at 190.5 200.66 0)
      (effects (font (size 1.524 1.524)) hide)
    )
    (property "Footprint" "antmicro-footprints:C_0402_1005Metric" (at 181.61 195.58 0)
      (effects (font (size 1.524 1.524)) (justify left) hide)
    )
    (property "Datasheet" "https://www.murata.com/products/productdetail?partno=GRM155R71H103KA88%23" (at 186.69 200.66 0)
      (effects (font (size 1.27 1.27)) hide)
    )
    (property "Manufacturer" "Murata" (at 176.53 195.58 0)
      (effects (font (size 1.524 1.524)) (justify left) hide)
    )
    (property "MPN" "GRM155R71H103KA88D" (at 179.07 195.58 0)
      (effects (font (size 1.524 1.524)) (justify left) hide)
    )
    (property "Val" "10n" (at 189.23 199.3836 90)
      (effects (font (size 1.27 1.27)) (justify right))
    )
    (property "License" "Apache-2.0" (at 209.55 180.34 0)
      (effects (font (size 1.27 1.27) (thickness 0.15)) (justify left bottom) hide)
    )
    (property "Author" "Antmicro" (at 212.09 180.34 0)
      (effects (font (size 1.27 1.27) (thickness 0.15)) (justify left bottom) hide)
    )
    (property "Voltage" "50V" (at 214.63 180.34 0)
      (effects (font (size 1.27 1.27)) (justify left bottom) hide)
    )
    (property "Dielectric" "X7R" (at 217.17 180.34 0)
      (effects (font (size 1.27 1.27)) (justify left bottom) hide)
    )
    (property "Public" "False" (at 219.71 180.34 0)
      (effects (font (size 1.27 1.27)) (justify left bottom) hide)
    )
    (pin "1")
    (pin "2")
    (instances
      (project "ecp5-dc-scm"
        (path ""
          (reference "C20") (unit 1)
        )
      )
    )
  )

  (symbol (lib_id "antmicroCapacitors0402:C_10n_0402") (at 287.02 115.57 90) (unit 1)
    (in_bom yes) (on_board yes) (dnp no)
    (property "Reference" "C23" (at 287.02 110.49 90)
      (effects (font (size 1.524 1.524)) (justify right))
    )
    (property "Value" "C_10n_0402" (at 290.83 115.57 0)
      (effects (font (size 1.524 1.524)) hide)
    )
    (property "Footprint" "antmicro-footprints:C_0402_1005Metric" (at 281.94 110.49 0)
      (effects (font (size 1.524 1.524)) (justify left) hide)
    )
    (property "Datasheet" "https://www.murata.com/products/productdetail?partno=GRM155R71H103KA88%23" (at 287.02 115.57 0)
      (effects (font (size 1.27 1.27)) hide)
    )
    (property "Manufacturer" "Murata" (at 276.86 110.49 0)
      (effects (font (size 1.524 1.524)) (justify left) hide)
    )
    (property "MPN" "GRM155R71H103KA88D" (at 279.4 110.49 0)
      (effects (font (size 1.524 1.524)) (justify left) hide)
    )
    (property "Val" "10n" (at 287.02 115.57 90)
      (effects (font (size 1.27 1.27)) (justify right))
    )
    (property "License" "Apache-2.0" (at 309.88 95.25 0)
      (effects (font (size 1.27 1.27) (thickness 0.15)) (justify left bottom) hide)
    )
    (property "Author" "Antmicro" (at 312.42 95.25 0)
      (effects (font (size 1.27 1.27) (thickness 0.15)) (justify left bottom) hide)
    )
    (property "Voltage" "50V" (at 314.96 95.25 0)
      (effects (font (size 1.27 1.27)) (justify left bottom) hide)
    )
    (property "Dielectric" "X7R" (at 317.5 95.25 0)
      (effects (font (size 1.27 1.27)) (justify left bottom) hide)
    )
    (property "Public" "False" (at 320.04 95.25 0)
      (effects (font (size 1.27 1.27)) (justify left bottom) hide)
    )
    (pin "1")
    (pin "2")
    (instances
      (project "ecp5-dc-scm"
        (path ""
          (reference "C23") (unit 1)
        )
      )
    )
  )

  (symbol (lib_id "antmicroCapacitors0402:C_4u7_0402") (at 279.4 137.16 90) (unit 1)
    (in_bom yes) (on_board yes) (dnp no)
    (property "Reference" "C22" (at 278.13 133.35 90)
      (effects (font (size 1.524 1.524)) (justify left))
    )
    (property "Value" "C_4u7_0402" (at 283.21 137.16 0)
      (effects (font (size 1.524 1.524)) hide)
    )
    (property "Footprint" "antmicro-footprints:C_0402_1005Metric" (at 274.32 132.08 0)
      (effects (font (size 1.524 1.524)) (justify left) hide)
    )
    (property "Datasheet" "https://www.murata.com/products/productdetail?partno=GRM155R61A475MEAA%23" (at 279.4 137.16 0)
      (effects (font (size 1.27 1.27)) hide)
    )
    (property "Manufacturer" "Murata" (at 269.24 132.08 0)
      (effects (font (size 1.524 1.524)) (justify left) hide)
    )
    (property "MPN" "GRM155R61A475MEAAD" (at 271.78 132.08 0)
      (effects (font (size 1.524 1.524)) (justify left) hide)
    )
    (property "Val" "4u7" (at 278.13 137.16 90)
      (effects (font (size 1.27 1.27)) (justify left))
    )
    (property "License" "Apache-2.0" (at 302.26 116.84 0)
      (effects (font (size 1.27 1.27) (thickness 0.15)) (justify left bottom) hide)
    )
    (property "Author" "Antmicro" (at 304.8 116.84 0)
      (effects (font (size 1.27 1.27) (thickness 0.15)) (justify left bottom) hide)
    )
    (property "Voltage" "" (at 307.34 116.84 0)
      (effects (font (size 1.27 1.27)) (justify left bottom) hide)
    )
    (property "Dielectric" "" (at 309.88 116.84 0)
      (effects (font (size 1.27 1.27)) (justify left bottom) hide)
    )
    (property "Public" "False" (at 312.42 116.84 0)
      (effects (font (size 1.27 1.27)) (justify left bottom) hide)
    )
    (pin "1")
    (pin "2")
    (instances
      (project "ecp5-dc-scm"
        (path ""
          (reference "C22") (unit 1)
        )
      )
    )
  )

  (symbol (lib_id "antmicroCapacitors0402:C_10n_0402") (at 293.37 137.16 90) (unit 1)
    (in_bom yes) (on_board yes) (dnp no)
    (property "Reference" "C25" (at 288.29 133.35 90)
      (effects (font (size 1.524 1.524)) (justify right))
    )
    (property "Value" "C_10n_0402" (at 297.18 137.16 0)
      (effects (font (size 1.524 1.524)) hide)
    )
    (property "Footprint" "antmicro-footprints:C_0402_1005Metric" (at 288.29 132.08 0)
      (effects (font (size 1.524 1.524)) (justify left) hide)
    )
    (property "Datasheet" "https://www.murata.com/products/productdetail?partno=GRM155R71H103KA88%23" (at 293.37 137.16 0)
      (effects (font (size 1.27 1.27)) hide)
    )
    (property "Manufacturer" "Murata" (at 283.21 132.08 0)
      (effects (font (size 1.524 1.524)) (justify left) hide)
    )
    (property "MPN" "GRM155R71H103KA88D" (at 285.75 132.08 0)
      (effects (font (size 1.524 1.524)) (justify left) hide)
    )
    (property "Val" "10n" (at 289.56 137.16 90)
      (effects (font (size 1.27 1.27)) (justify right))
    )
    (property "License" "Apache-2.0" (at 316.23 116.84 0)
      (effects (font (size 1.27 1.27) (thickness 0.15)) (justify left bottom) hide)
    )
    (property "Author" "Antmicro" (at 318.77 116.84 0)
      (effects (font (size 1.27 1.27) (thickness 0.15)) (justify left bottom) hide)
    )
    (property "Voltage" "50V" (at 321.31 116.84 0)
      (effects (font (size 1.27 1.27)) (justify left bottom) hide)
    )
    (property "Dielectric" "X7R" (at 323.85 116.84 0)
      (effects (font (size 1.27 1.27)) (justify left bottom) hide)
    )
    (property "Public" "False" (at 326.39 116.84 0)
      (effects (font (size 1.27 1.27)) (justify left bottom) hide)
    )
    (pin "1")
    (pin "2")
    (instances
      (project "ecp5-dc-scm"
        (path ""
          (reference "C25") (unit 1)
        )
      )
    )
  )

  (symbol (lib_id "antmicropower:GND") (at 186.69 201.93 0) (unit 1)
    (in_bom yes) (on_board yes) (dnp no)
    (property "Reference" "#PWR030" (at 186.69 208.28 0)
      (effects (font (size 1.27 1.27)) hide)
    )
    (property "Value" "GND" (at 186.817 206.3242 0)
      (effects (font (size 1.27 1.27)))
    )
    (property "Footprint" "" (at 186.69 201.93 0)
      (effects (font (size 1.27 1.27)) hide)
    )
    (property "Datasheet" "" (at 186.69 201.93 0)
      (effects (font (size 1.27 1.27)) hide)
    )
    (property "Author" "Antmicro" (at 195.58 209.55 0)
      (effects (font (size 1.27 1.27) (thickness 0.15)) (justify left bottom) hide)
    )
    (property "License" "Apache-2.0" (at 195.58 212.09 0)
      (effects (font (size 1.27 1.27) (thickness 0.15)) (justify left bottom) hide)
    )
    (pin "1")
    (instances
      (project "ecp5-dc-scm"
        (path ""
          (reference "#PWR030") (unit 1)
        )
      )
    )
  )

  (symbol (lib_id "antmicropower:GND") (at 196.85 201.93 0) (unit 1)
    (in_bom yes) (on_board yes) (dnp no)
    (property "Reference" "#PWR05" (at 196.85 208.28 0)
      (effects (font (size 1.27 1.27)) hide)
    )
    (property "Value" "GND" (at 196.977 206.3242 0)
      (effects (font (size 1.27 1.27)))
    )
    (property "Footprint" "" (at 196.85 201.93 0)
      (effects (font (size 1.27 1.27)) hide)
    )
    (property "Datasheet" "" (at 196.85 201.93 0)
      (effects (font (size 1.27 1.27)) hide)
    )
    (property "Author" "Antmicro" (at 205.74 209.55 0)
      (effects (font (size 1.27 1.27) (thickness 0.15)) (justify left bottom) hide)
    )
    (property "License" "Apache-2.0" (at 205.74 212.09 0)
      (effects (font (size 1.27 1.27) (thickness 0.15)) (justify left bottom) hide)
    )
    (pin "1")
    (instances
      (project "ecp5-dc-scm"
        (path ""
          (reference "#PWR05") (unit 1)
        )
      )
    )
  )

  (symbol (lib_id "antmicropower:GND") (at 293.37 142.24 0) (unit 1)
    (in_bom yes) (on_board yes) (dnp no)
    (property "Reference" "#PWR07" (at 293.37 148.59 0)
      (effects (font (size 1.27 1.27)) hide)
    )
    (property "Value" "GND" (at 293.497 146.6342 0)
      (effects (font (size 1.27 1.27)))
    )
    (property "Footprint" "" (at 293.37 142.24 0)
      (effects (font (size 1.27 1.27)) hide)
    )
    (property "Datasheet" "" (at 293.37 142.24 0)
      (effects (font (size 1.27 1.27)) hide)
    )
    (property "Author" "Antmicro" (at 302.26 149.86 0)
      (effects (font (size 1.27 1.27) (thickness 0.15)) (justify left bottom) hide)
    )
    (property "License" "Apache-2.0" (at 302.26 152.4 0)
      (effects (font (size 1.27 1.27) (thickness 0.15)) (justify left bottom) hide)
    )
    (pin "1")
    (instances
      (project "ecp5-dc-scm"
        (path ""
          (reference "#PWR07") (unit 1)
        )
      )
    )
  )

  (symbol (lib_id "antmicropower:GND") (at 287.02 120.65 0) (unit 1)
    (in_bom yes) (on_board yes) (dnp no)
    (property "Reference" "#PWR06" (at 287.02 127 0)
      (effects (font (size 1.27 1.27)) hide)
    )
    (property "Value" "GND" (at 287.02 124.46 0)
      (effects (font (size 1.27 1.27)))
    )
    (property "Footprint" "" (at 287.02 120.65 0)
      (effects (font (size 1.27 1.27)) hide)
    )
    (property "Datasheet" "" (at 287.02 120.65 0)
      (effects (font (size 1.27 1.27)) hide)
    )
    (property "Author" "Antmicro" (at 295.91 128.27 0)
      (effects (font (size 1.27 1.27) (thickness 0.15)) (justify left bottom) hide)
    )
    (property "License" "Apache-2.0" (at 295.91 130.81 0)
      (effects (font (size 1.27 1.27) (thickness 0.15)) (justify left bottom) hide)
    )
    (pin "1")
    (instances
      (project "ecp5-dc-scm"
        (path ""
          (reference "#PWR06") (unit 1)
        )
      )
    )
  )

  (symbol (lib_id "antmicropower:GND") (at 231.14 175.26 0) (unit 1)
    (in_bom yes) (on_board yes) (dnp no)
    (property "Reference" "#PWR04" (at 231.14 181.61 0)
      (effects (font (size 1.27 1.27)) hide)
    )
    (property "Value" "GND" (at 231.267 179.6542 0)
      (effects (font (size 1.27 1.27)))
    )
    (property "Footprint" "" (at 231.14 175.26 0)
      (effects (font (size 1.27 1.27)) hide)
    )
    (property "Datasheet" "" (at 231.14 175.26 0)
      (effects (font (size 1.27 1.27)) hide)
    )
    (property "Author" "Antmicro" (at 240.03 182.88 0)
      (effects (font (size 1.27 1.27) (thickness 0.15)) (justify left bottom) hide)
    )
    (property "License" "Apache-2.0" (at 240.03 185.42 0)
      (effects (font (size 1.27 1.27) (thickness 0.15)) (justify left bottom) hide)
    )
    (pin "1")
    (instances
      (project "ecp5-dc-scm"
        (path ""
          (reference "#PWR04") (unit 1)
        )
      )
    )
  )

  (symbol (lib_id "antmicroResistors0402:R_10k2_0402") (at 124.46 196.85 270) (mirror x) (unit 1)
    (in_bom yes) (on_board yes) (dnp no)
    (property "Reference" "R1" (at 125.73 193.04 90)
      (effects (font (size 1.524 1.524)) (justify left))
    )
    (property "Value" "R_10k2_0402" (at 120.65 196.85 0)
      (effects (font (size 1.524 1.524)) hide)
    )
    (property "Footprint" "antmicro-footprints:R_0402_1005Metric" (at 129.54 191.77 0)
      (effects (font (size 1.524 1.524)) (justify left) hide)
    )
    (property "Datasheet" "https://www.bourns.com/docs/product-datasheets/cr.pdf" (at 124.46 196.85 0)
      (effects (font (size 1.27 1.27)) hide)
    )
    (property "Manufacturer" "Bourns" (at 134.62 191.77 0)
      (effects (font (size 1.524 1.524)) (justify left) hide)
    )
    (property "MPN" "CR0402-FX-1022GLF" (at 132.08 191.77 0)
      (effects (font (size 1.524 1.524)) (justify left) hide)
    )
    (property "Val" "10k2" (at 125.73 195.58 90)
      (effects (font (size 1.27 1.27)) (justify left))
    )
    (property "License" "Apache-2.0" (at 99.06 176.53 0)
      (effects (font (size 1.27 1.27) (thickness 0.15)) (justify left bottom) hide)
    )
    (property "Author" "Antmicro" (at 96.52 176.53 0)
      (effects (font (size 1.27 1.27) (thickness 0.15)) (justify left bottom) hide)
    )
    (property "Tolerance" "1%" (at 114.3 176.53 0)
      (effects (font (size 1.27 1.27)) (justify left bottom) hide)
    )
    (property "Public" "False" (at 93.98 176.53 0)
      (effects (font (size 1.27 1.27)) (justify left bottom) hide)
    )
    (pin "1")
    (pin "2")
    (instances
      (project "ecp5-dc-scm"
        (path ""
          (reference "R1") (unit 1)
        )
      )
    )
  )

  (symbol (lib_id "antmicroResistors0402:R_10k2_0402") (at 120.65 196.85 270) (mirror x) (unit 1)
    (in_bom yes) (on_board yes) (dnp no)
    (property "Reference" "R2" (at 119.38 193.04 90)
      (effects (font (size 1.524 1.524)) (justify right))
    )
    (property "Value" "R_10k2_0402" (at 116.84 196.85 0)
      (effects (font (size 1.524 1.524)) hide)
    )
    (property "Footprint" "antmicro-footprints:R_0402_1005Metric" (at 125.73 191.77 0)
      (effects (font (size 1.524 1.524)) (justify left) hide)
    )
    (property "Datasheet" "https://www.bourns.com/docs/product-datasheets/cr.pdf" (at 120.65 196.85 0)
      (effects (font (size 1.27 1.27)) hide)
    )
    (property "Manufacturer" "Bourns" (at 130.81 191.77 0)
      (effects (font (size 1.524 1.524)) (justify left) hide)
    )
    (property "MPN" "CR0402-FX-1022GLF" (at 128.27 191.77 0)
      (effects (font (size 1.524 1.524)) (justify left) hide)
    )
    (property "Val" "10k2" (at 119.38 195.58 90)
      (effects (font (size 1.27 1.27)) (justify right))
    )
    (property "License" "Apache-2.0" (at 95.25 176.53 0)
      (effects (font (size 1.27 1.27) (thickness 0.15)) (justify left bottom) hide)
    )
    (property "Author" "Antmicro" (at 92.71 176.53 0)
      (effects (font (size 1.27 1.27) (thickness 0.15)) (justify left bottom) hide)
    )
    (property "Tolerance" "1%" (at 110.49 176.53 0)
      (effects (font (size 1.27 1.27)) (justify left bottom) hide)
    )
    (property "Public" "False" (at 90.17 176.53 0)
      (effects (font (size 1.27 1.27)) (justify left bottom) hide)
    )
    (pin "1")
    (pin "2")
    (instances
      (project "ecp5-dc-scm"
        (path ""
          (reference "R2") (unit 1)
        )
      )
    )
  )

  (symbol (lib_id "antmicroResistors0402:R_10k2_0402") (at 111.76 196.85 270) (mirror x) (unit 1)
    (in_bom yes) (on_board yes) (dnp no)
    (property "Reference" "R3" (at 110.49 193.04 90)
      (effects (font (size 1.524 1.524)) (justify right))
    )
    (property "Value" "R_10k2_0402" (at 107.95 196.85 0)
      (effects (font (size 1.524 1.524)) hide)
    )
    (property "Footprint" "antmicro-footprints:R_0402_1005Metric" (at 116.84 191.77 0)
      (effects (font (size 1.524 1.524)) (justify left) hide)
    )
    (property "Datasheet" "https://www.bourns.com/docs/product-datasheets/cr.pdf" (at 111.76 196.85 0)
      (effects (font (size 1.27 1.27)) hide)
    )
    (property "Manufacturer" "Bourns" (at 121.92 191.77 0)
      (effects (font (size 1.524 1.524)) (justify left) hide)
    )
    (property "MPN" "CR0402-FX-1022GLF" (at 119.38 191.77 0)
      (effects (font (size 1.524 1.524)) (justify left) hide)
    )
    (property "Val" "10k2" (at 110.49 195.58 90)
      (effects (font (size 1.27 1.27)) (justify right))
    )
    (property "License" "Apache-2.0" (at 86.36 176.53 0)
      (effects (font (size 1.27 1.27) (thickness 0.15)) (justify left bottom) hide)
    )
    (property "Author" "Antmicro" (at 83.82 176.53 0)
      (effects (font (size 1.27 1.27) (thickness 0.15)) (justify left bottom) hide)
    )
    (property "Tolerance" "1%" (at 101.6 176.53 0)
      (effects (font (size 1.27 1.27)) (justify left bottom) hide)
    )
    (property "Public" "False" (at 81.28 176.53 0)
      (effects (font (size 1.27 1.27)) (justify left bottom) hide)
    )
    (pin "1")
    (pin "2")
    (instances
      (project "ecp5-dc-scm"
        (path ""
          (reference "R3") (unit 1)
        )
      )
    )
  )

  (symbol (lib_id "antmicroResistors0402:R_10k2_0402") (at 102.87 196.85 270) (mirror x) (unit 1)
    (in_bom yes) (on_board yes) (dnp no)
    (property "Reference" "R4" (at 101.6 193.04 90)
      (effects (font (size 1.524 1.524)) (justify right))
    )
    (property "Value" "R_10k2_0402" (at 99.06 196.85 0)
      (effects (font (size 1.524 1.524)) hide)
    )
    (property "Footprint" "antmicro-footprints:R_0402_1005Metric" (at 107.95 191.77 0)
      (effects (font (size 1.524 1.524)) (justify left) hide)
    )
    (property "Datasheet" "https://www.bourns.com/docs/product-datasheets/cr.pdf" (at 102.87 196.85 0)
      (effects (font (size 1.27 1.27)) hide)
    )
    (property "Manufacturer" "Bourns" (at 113.03 191.77 0)
      (effects (font (size 1.524 1.524)) (justify left) hide)
    )
    (property "MPN" "CR0402-FX-1022GLF" (at 110.49 191.77 0)
      (effects (font (size 1.524 1.524)) (justify left) hide)
    )
    (property "Val" "10k2" (at 101.6 195.58 90)
      (effects (font (size 1.27 1.27)) (justify right))
    )
    (property "License" "Apache-2.0" (at 77.47 176.53 0)
      (effects (font (size 1.27 1.27) (thickness 0.15)) (justify left bottom) hide)
    )
    (property "Author" "Antmicro" (at 74.93 176.53 0)
      (effects (font (size 1.27 1.27) (thickness 0.15)) (justify left bottom) hide)
    )
    (property "Tolerance" "1%" (at 92.71 176.53 0)
      (effects (font (size 1.27 1.27)) (justify left bottom) hide)
    )
    (property "Public" "False" (at 72.39 176.53 0)
      (effects (font (size 1.27 1.27)) (justify left bottom) hide)
    )
    (pin "1")
    (pin "2")
    (instances
      (project "ecp5-dc-scm"
        (path ""
          (reference "R4") (unit 1)
        )
      )
    )
  )

  (symbol (lib_id "antmicroResistors0402:R_10k2_0402") (at 92.71 196.85 270) (mirror x) (unit 1)
    (in_bom yes) (on_board yes) (dnp no)
    (property "Reference" "R5" (at 91.44 193.04 90)
      (effects (font (size 1.524 1.524)) (justify right))
    )
    (property "Value" "R_10k2_0402" (at 88.9 196.85 0)
      (effects (font (size 1.524 1.524)) hide)
    )
    (property "Footprint" "antmicro-footprints:R_0402_1005Metric" (at 97.79 191.77 0)
      (effects (font (size 1.524 1.524)) (justify left) hide)
    )
    (property "Datasheet" "https://www.bourns.com/docs/product-datasheets/cr.pdf" (at 92.71 196.85 0)
      (effects (font (size 1.27 1.27)) hide)
    )
    (property "Manufacturer" "Bourns" (at 102.87 191.77 0)
      (effects (font (size 1.524 1.524)) (justify left) hide)
    )
    (property "MPN" "CR0402-FX-1022GLF" (at 100.33 191.77 0)
      (effects (font (size 1.524 1.524)) (justify left) hide)
    )
    (property "Val" "10k2" (at 91.44 195.58 90)
      (effects (font (size 1.27 1.27)) (justify right))
    )
    (property "License" "Apache-2.0" (at 67.31 176.53 0)
      (effects (font (size 1.27 1.27) (thickness 0.15)) (justify left bottom) hide)
    )
    (property "Author" "Antmicro" (at 64.77 176.53 0)
      (effects (font (size 1.27 1.27) (thickness 0.15)) (justify left bottom) hide)
    )
    (property "Tolerance" "1%" (at 82.55 176.53 0)
      (effects (font (size 1.27 1.27)) (justify left bottom) hide)
    )
    (property "Public" "False" (at 62.23 176.53 0)
      (effects (font (size 1.27 1.27)) (justify left bottom) hide)
    )
    (pin "1")
    (pin "2")
    (instances
      (project "ecp5-dc-scm"
        (path ""
          (reference "R5") (unit 1)
        )
      )
    )
  )

  (symbol (lib_id "antmicroResistors0402:R_10k2_0402") (at 83.82 196.85 270) (mirror x) (unit 1)
    (in_bom yes) (on_board yes) (dnp no)
    (property "Reference" "R6" (at 82.55 193.04 90)
      (effects (font (size 1.524 1.524)) (justify right))
    )
    (property "Value" "R_10k2_0402" (at 80.01 196.85 0)
      (effects (font (size 1.524 1.524)) hide)
    )
    (property "Footprint" "antmicro-footprints:R_0402_1005Metric" (at 88.9 191.77 0)
      (effects (font (size 1.524 1.524)) (justify left) hide)
    )
    (property "Datasheet" "https://www.bourns.com/docs/product-datasheets/cr.pdf" (at 83.82 196.85 0)
      (effects (font (size 1.27 1.27)) hide)
    )
    (property "Manufacturer" "Bourns" (at 93.98 191.77 0)
      (effects (font (size 1.524 1.524)) (justify left) hide)
    )
    (property "MPN" "CR0402-FX-1022GLF" (at 91.44 191.77 0)
      (effects (font (size 1.524 1.524)) (justify left) hide)
    )
    (property "Val" "10k2" (at 82.55 195.58 90)
      (effects (font (size 1.27 1.27)) (justify right))
    )
    (property "License" "Apache-2.0" (at 58.42 176.53 0)
      (effects (font (size 1.27 1.27) (thickness 0.15)) (justify left bottom) hide)
    )
    (property "Author" "Antmicro" (at 55.88 176.53 0)
      (effects (font (size 1.27 1.27) (thickness 0.15)) (justify left bottom) hide)
    )
    (property "Tolerance" "1%" (at 73.66 176.53 0)
      (effects (font (size 1.27 1.27)) (justify left bottom) hide)
    )
    (property "Public" "False" (at 53.34 176.53 0)
      (effects (font (size 1.27 1.27)) (justify left bottom) hide)
    )
    (pin "1")
    (pin "2")
    (instances
      (project "ecp5-dc-scm"
        (path ""
          (reference "R6") (unit 1)
        )
      )
    )
  )

  (symbol (lib_id "antmicroResistors0402:R_10k2_0402") (at 74.93 196.85 270) (mirror x) (unit 1)
    (in_bom yes) (on_board yes) (dnp no)
    (property "Reference" "R7" (at 73.66 193.04 90)
      (effects (font (size 1.524 1.524)) (justify right))
    )
    (property "Value" "R_10k2_0402" (at 71.12 196.85 0)
      (effects (font (size 1.524 1.524)) hide)
    )
    (property "Footprint" "antmicro-footprints:R_0402_1005Metric" (at 80.01 191.77 0)
      (effects (font (size 1.524 1.524)) (justify left) hide)
    )
    (property "Datasheet" "https://www.bourns.com/docs/product-datasheets/cr.pdf" (at 74.93 196.85 0)
      (effects (font (size 1.27 1.27)) hide)
    )
    (property "Manufacturer" "Bourns" (at 85.09 191.77 0)
      (effects (font (size 1.524 1.524)) (justify left) hide)
    )
    (property "MPN" "CR0402-FX-1022GLF" (at 82.55 191.77 0)
      (effects (font (size 1.524 1.524)) (justify left) hide)
    )
    (property "Val" "10k2" (at 73.66 195.58 90)
      (effects (font (size 1.27 1.27)) (justify right))
    )
    (property "License" "Apache-2.0" (at 49.53 176.53 0)
      (effects (font (size 1.27 1.27) (thickness 0.15)) (justify left bottom) hide)
    )
    (property "Author" "Antmicro" (at 46.99 176.53 0)
      (effects (font (size 1.27 1.27) (thickness 0.15)) (justify left bottom) hide)
    )
    (property "Tolerance" "1%" (at 64.77 176.53 0)
      (effects (font (size 1.27 1.27)) (justify left bottom) hide)
    )
    (property "Public" "False" (at 44.45 176.53 0)
      (effects (font (size 1.27 1.27)) (justify left bottom) hide)
    )
    (pin "1")
    (pin "2")
    (instances
      (project "ecp5-dc-scm"
        (path ""
          (reference "R7") (unit 1)
        )
      )
    )
  )

  (symbol (lib_id "antmicroResistors0402:R_10k2_0402") (at 58.42 196.85 270) (mirror x) (unit 1)
    (in_bom yes) (on_board yes) (dnp no)
    (property "Reference" "R10" (at 57.15 193.04 90)
      (effects (font (size 1.524 1.524)) (justify right))
    )
    (property "Value" "R_10k2_0402" (at 54.61 196.85 0)
      (effects (font (size 1.524 1.524)) hide)
    )
    (property "Footprint" "antmicro-footprints:R_0402_1005Metric" (at 63.5 191.77 0)
      (effects (font (size 1.524 1.524)) (justify left) hide)
    )
    (property "Datasheet" "https://www.bourns.com/docs/product-datasheets/cr.pdf" (at 58.42 196.85 0)
      (effects (font (size 1.27 1.27)) hide)
    )
    (property "Manufacturer" "Bourns" (at 68.58 191.77 0)
      (effects (font (size 1.524 1.524)) (justify left) hide)
    )
    (property "MPN" "CR0402-FX-1022GLF" (at 66.04 191.77 0)
      (effects (font (size 1.524 1.524)) (justify left) hide)
    )
    (property "Val" "10k2" (at 57.15 195.58 90)
      (effects (font (size 1.27 1.27)) (justify right))
    )
    (property "License" "Apache-2.0" (at 33.02 176.53 0)
      (effects (font (size 1.27 1.27) (thickness 0.15)) (justify left bottom) hide)
    )
    (property "Author" "Antmicro" (at 30.48 176.53 0)
      (effects (font (size 1.27 1.27) (thickness 0.15)) (justify left bottom) hide)
    )
    (property "Tolerance" "1%" (at 48.26 176.53 0)
      (effects (font (size 1.27 1.27)) (justify left bottom) hide)
    )
    (property "Public" "False" (at 27.94 176.53 0)
      (effects (font (size 1.27 1.27)) (justify left bottom) hide)
    )
    (pin "1")
    (pin "2")
    (instances
      (project "ecp5-dc-scm"
        (path ""
          (reference "R10") (unit 1)
        )
      )
    )
  )

  (symbol (lib_id "antmicroResistors0402:R_10k2_0402") (at 40.64 196.85 270) (mirror x) (unit 1)
    (in_bom yes) (on_board yes) (dnp no)
    (property "Reference" "R12" (at 39.37 193.04 90)
      (effects (font (size 1.524 1.524)) (justify right))
    )
    (property "Value" "R_10k2_0402" (at 36.83 196.85 0)
      (effects (font (size 1.524 1.524)) hide)
    )
    (property "Footprint" "antmicro-footprints:R_0402_1005Metric" (at 45.72 191.77 0)
      (effects (font (size 1.524 1.524)) (justify left) hide)
    )
    (property "Datasheet" "https://www.bourns.com/docs/product-datasheets/cr.pdf" (at 40.64 196.85 0)
      (effects (font (size 1.27 1.27)) hide)
    )
    (property "Manufacturer" "Bourns" (at 50.8 191.77 0)
      (effects (font (size 1.524 1.524)) (justify left) hide)
    )
    (property "MPN" "CR0402-FX-1022GLF" (at 48.26 191.77 0)
      (effects (font (size 1.524 1.524)) (justify left) hide)
    )
    (property "Val" "10k2" (at 39.37 195.58 90)
      (effects (font (size 1.27 1.27)) (justify right))
    )
    (property "License" "Apache-2.0" (at 15.24 176.53 0)
      (effects (font (size 1.27 1.27) (thickness 0.15)) (justify left bottom) hide)
    )
    (property "Author" "Antmicro" (at 12.7 176.53 0)
      (effects (font (size 1.27 1.27) (thickness 0.15)) (justify left bottom) hide)
    )
    (property "Tolerance" "1%" (at 30.48 176.53 0)
      (effects (font (size 1.27 1.27)) (justify left bottom) hide)
    )
    (property "Public" "False" (at 10.16 176.53 0)
      (effects (font (size 1.27 1.27)) (justify left bottom) hide)
    )
    (pin "1")
    (pin "2")
    (instances
      (project "ecp5-dc-scm"
        (path ""
          (reference "R12") (unit 1)
        )
      )
    )
  )

  (symbol (lib_id "antmicroResistors0402:R_10k2_0402") (at 49.53 196.85 270) (mirror x) (unit 1)
    (in_bom yes) (on_board yes) (dnp no)
    (property "Reference" "R11" (at 48.26 193.04 90)
      (effects (font (size 1.524 1.524)) (justify right))
    )
    (property "Value" "R_10k2_0402" (at 45.72 196.85 0)
      (effects (font (size 1.524 1.524)) hide)
    )
    (property "Footprint" "antmicro-footprints:R_0402_1005Metric" (at 54.61 191.77 0)
      (effects (font (size 1.524 1.524)) (justify left) hide)
    )
    (property "Datasheet" "https://www.bourns.com/docs/product-datasheets/cr.pdf" (at 49.53 196.85 0)
      (effects (font (size 1.27 1.27)) hide)
    )
    (property "Manufacturer" "Bourns" (at 59.69 191.77 0)
      (effects (font (size 1.524 1.524)) (justify left) hide)
    )
    (property "MPN" "CR0402-FX-1022GLF" (at 57.15 191.77 0)
      (effects (font (size 1.524 1.524)) (justify left) hide)
    )
    (property "Val" "10k2" (at 48.26 195.58 90)
      (effects (font (size 1.27 1.27)) (justify right))
    )
    (property "License" "Apache-2.0" (at 24.13 176.53 0)
      (effects (font (size 1.27 1.27) (thickness 0.15)) (justify left bottom) hide)
    )
    (property "Author" "Antmicro" (at 21.59 176.53 0)
      (effects (font (size 1.27 1.27) (thickness 0.15)) (justify left bottom) hide)
    )
    (property "Tolerance" "1%" (at 39.37 176.53 0)
      (effects (font (size 1.27 1.27)) (justify left bottom) hide)
    )
    (property "Public" "False" (at 19.05 176.53 0)
      (effects (font (size 1.27 1.27)) (justify left bottom) hide)
    )
    (pin "1")
    (pin "2")
    (instances
      (project "ecp5-dc-scm"
        (path ""
          (reference "R11") (unit 1)
        )
      )
    )
  )

  (symbol (lib_id "antmicroCapacitors0402:C_10n_0402") (at 264.16 93.98 270) (mirror x) (unit 1)
    (in_bom yes) (on_board yes) (dnp no)
    (property "Reference" "C12" (at 264.16 88.9 90)
      (effects (font (size 1.524 1.524)) (justify left))
    )
    (property "Value" "C_10n_0402" (at 260.35 93.98 0)
      (effects (font (size 1.524 1.524)) hide)
    )
    (property "Footprint" "antmicro-footprints:C_0402_1005Metric" (at 269.24 88.9 0)
      (effects (font (size 1.524 1.524)) (justify left) hide)
    )
    (property "Datasheet" "https://www.murata.com/products/productdetail?partno=GRM155R71H103KA88%23" (at 264.16 93.98 0)
      (effects (font (size 1.27 1.27)) hide)
    )
    (property "Manufacturer" "Murata" (at 274.32 88.9 0)
      (effects (font (size 1.524 1.524)) (justify left) hide)
    )
    (property "MPN" "GRM155R71H103KA88D" (at 271.78 88.9 0)
      (effects (font (size 1.524 1.524)) (justify left) hide)
    )
    (property "Val" "10n" (at 264.16 93.98 90)
      (effects (font (size 1.27 1.27)) (justify left))
    )
    (property "License" "Apache-2.0" (at 241.3 73.66 0)
      (effects (font (size 1.27 1.27) (thickness 0.15)) (justify left bottom) hide)
    )
    (property "Author" "Antmicro" (at 238.76 73.66 0)
      (effects (font (size 1.27 1.27) (thickness 0.15)) (justify left bottom) hide)
    )
    (property "Voltage" "50V" (at 236.22 73.66 0)
      (effects (font (size 1.27 1.27)) (justify left bottom) hide)
    )
    (property "Dielectric" "X7R" (at 233.68 73.66 0)
      (effects (font (size 1.27 1.27)) (justify left bottom) hide)
    )
    (property "Public" "False" (at 231.14 73.66 0)
      (effects (font (size 1.27 1.27)) (justify left bottom) hide)
    )
    (pin "1")
    (pin "2")
    (instances
      (project "ecp5-dc-scm"
        (path ""
          (reference "C12") (unit 1)
        )
      )
    )
  )

  (symbol (lib_id "antmicroCapacitors0402:C_10n_0402") (at 257.81 93.98 270) (mirror x) (unit 1)
    (in_bom yes) (on_board yes) (dnp no)
    (property "Reference" "C15" (at 257.81 88.9 90)
      (effects (font (size 1.524 1.524)) (justify left))
    )
    (property "Value" "C_10n_0402" (at 254 93.98 0)
      (effects (font (size 1.524 1.524)) hide)
    )
    (property "Footprint" "antmicro-footprints:C_0402_1005Metric" (at 262.89 88.9 0)
      (effects (font (size 1.524 1.524)) (justify left) hide)
    )
    (property "Datasheet" "https://www.murata.com/products/productdetail?partno=GRM155R71H103KA88%23" (at 257.81 93.98 0)
      (effects (font (size 1.27 1.27)) hide)
    )
    (property "Manufacturer" "Murata" (at 267.97 88.9 0)
      (effects (font (size 1.524 1.524)) (justify left) hide)
    )
    (property "MPN" "GRM155R71H103KA88D" (at 265.43 88.9 0)
      (effects (font (size 1.524 1.524)) (justify left) hide)
    )
    (property "Val" "10n" (at 257.81 93.98 90)
      (effects (font (size 1.27 1.27)) (justify left))
    )
    (property "License" "Apache-2.0" (at 234.95 73.66 0)
      (effects (font (size 1.27 1.27) (thickness 0.15)) (justify left bottom) hide)
    )
    (property "Author" "Antmicro" (at 232.41 73.66 0)
      (effects (font (size 1.27 1.27) (thickness 0.15)) (justify left bottom) hide)
    )
    (property "Voltage" "50V" (at 229.87 73.66 0)
      (effects (font (size 1.27 1.27)) (justify left bottom) hide)
    )
    (property "Dielectric" "X7R" (at 227.33 73.66 0)
      (effects (font (size 1.27 1.27)) (justify left bottom) hide)
    )
    (property "Public" "False" (at 224.79 73.66 0)
      (effects (font (size 1.27 1.27)) (justify left bottom) hide)
    )
    (pin "1")
    (pin "2")
    (instances
      (project "ecp5-dc-scm"
        (path ""
          (reference "C15") (unit 1)
        )
      )
    )
  )

  (symbol (lib_id "antmicroCapacitors0402:C_10n_0402") (at 276.86 93.98 270) (mirror x) (unit 1)
    (in_bom yes) (on_board yes) (dnp no)
    (property "Reference" "C7" (at 276.86 88.9 90)
      (effects (font (size 1.524 1.524)) (justify left))
    )
    (property "Value" "C_10n_0402" (at 273.05 93.98 0)
      (effects (font (size 1.524 1.524)) hide)
    )
    (property "Footprint" "antmicro-footprints:C_0402_1005Metric" (at 281.94 88.9 0)
      (effects (font (size 1.524 1.524)) (justify left) hide)
    )
    (property "Datasheet" "https://www.murata.com/products/productdetail?partno=GRM155R71H103KA88%23" (at 276.86 93.98 0)
      (effects (font (size 1.27 1.27)) hide)
    )
    (property "Manufacturer" "Murata" (at 287.02 88.9 0)
      (effects (font (size 1.524 1.524)) (justify left) hide)
    )
    (property "MPN" "GRM155R71H103KA88D" (at 284.48 88.9 0)
      (effects (font (size 1.524 1.524)) (justify left) hide)
    )
    (property "Val" "10n" (at 276.86 93.98 90)
      (effects (font (size 1.27 1.27)) (justify left))
    )
    (property "License" "Apache-2.0" (at 254 73.66 0)
      (effects (font (size 1.27 1.27) (thickness 0.15)) (justify left bottom) hide)
    )
    (property "Author" "Antmicro" (at 251.46 73.66 0)
      (effects (font (size 1.27 1.27) (thickness 0.15)) (justify left bottom) hide)
    )
    (property "Voltage" "50V" (at 248.92 73.66 0)
      (effects (font (size 1.27 1.27)) (justify left bottom) hide)
    )
    (property "Dielectric" "X7R" (at 246.38 73.66 0)
      (effects (font (size 1.27 1.27)) (justify left bottom) hide)
    )
    (property "Public" "False" (at 243.84 73.66 0)
      (effects (font (size 1.27 1.27)) (justify left bottom) hide)
    )
    (pin "1")
    (pin "2")
    (instances
      (project "ecp5-dc-scm"
        (path ""
          (reference "C7") (unit 1)
        )
      )
    )
  )

  (symbol (lib_id "antmicroCapacitors0402:C_10n_0402") (at 270.51 93.98 270) (mirror x) (unit 1)
    (in_bom yes) (on_board yes) (dnp no)
    (property "Reference" "C9" (at 270.51 88.9 90)
      (effects (font (size 1.524 1.524)) (justify left))
    )
    (property "Value" "C_10n_0402" (at 266.7 93.98 0)
      (effects (font (size 1.524 1.524)) hide)
    )
    (property "Footprint" "antmicro-footprints:C_0402_1005Metric" (at 275.59 88.9 0)
      (effects (font (size 1.524 1.524)) (justify left) hide)
    )
    (property "Datasheet" "https://www.murata.com/products/productdetail?partno=GRM155R71H103KA88%23" (at 270.51 93.98 0)
      (effects (font (size 1.27 1.27)) hide)
    )
    (property "Manufacturer" "Murata" (at 280.67 88.9 0)
      (effects (font (size 1.524 1.524)) (justify left) hide)
    )
    (property "MPN" "GRM155R71H103KA88D" (at 278.13 88.9 0)
      (effects (font (size 1.524 1.524)) (justify left) hide)
    )
    (property "Val" "10n" (at 270.51 93.98 90)
      (effects (font (size 1.27 1.27)) (justify left))
    )
    (property "License" "Apache-2.0" (at 247.65 73.66 0)
      (effects (font (size 1.27 1.27) (thickness 0.15)) (justify left bottom) hide)
    )
    (property "Author" "Antmicro" (at 245.11 73.66 0)
      (effects (font (size 1.27 1.27) (thickness 0.15)) (justify left bottom) hide)
    )
    (property "Voltage" "50V" (at 242.57 73.66 0)
      (effects (font (size 1.27 1.27)) (justify left bottom) hide)
    )
    (property "Dielectric" "X7R" (at 240.03 73.66 0)
      (effects (font (size 1.27 1.27)) (justify left bottom) hide)
    )
    (property "Public" "False" (at 237.49 73.66 0)
      (effects (font (size 1.27 1.27)) (justify left bottom) hide)
    )
    (pin "1")
    (pin "2")
    (instances
      (project "ecp5-dc-scm"
        (path ""
          (reference "C9") (unit 1)
        )
      )
    )
  )

  (symbol (lib_id "antmicroCapacitors0402:C_10n_0402") (at 133.35 123.19 90) (unit 1)
    (in_bom yes) (on_board yes) (dnp no)
    (property "Reference" "C13" (at 127 119.38 90)
      (effects (font (size 1.524 1.524)) (justify right))
    )
    (property "Value" "C_10n_0402" (at 137.16 123.19 0)
      (effects (font (size 1.524 1.524)) hide)
    )
    (property "Footprint" "antmicro-footprints:C_0402_1005Metric" (at 128.27 118.11 0)
      (effects (font (size 1.524 1.524)) (justify left) hide)
    )
    (property "Datasheet" "https://www.murata.com/products/productdetail?partno=GRM155R71H103KA88%23" (at 133.35 123.19 0)
      (effects (font (size 1.27 1.27)) hide)
    )
    (property "Manufacturer" "Murata" (at 123.19 118.11 0)
      (effects (font (size 1.524 1.524)) (justify left) hide)
    )
    (property "MPN" "GRM155R71H103KA88D" (at 125.73 118.11 0)
      (effects (font (size 1.524 1.524)) (justify left) hide)
    )
    (property "Val" "10n" (at 128.27 121.92 90)
      (effects (font (size 1.27 1.27)) (justify right))
    )
    (property "License" "Apache-2.0" (at 156.21 102.87 0)
      (effects (font (size 1.27 1.27) (thickness 0.15)) (justify left bottom) hide)
    )
    (property "Author" "Antmicro" (at 158.75 102.87 0)
      (effects (font (size 1.27 1.27) (thickness 0.15)) (justify left bottom) hide)
    )
    (property "Voltage" "50V" (at 161.29 102.87 0)
      (effects (font (size 1.27 1.27)) (justify left bottom) hide)
    )
    (property "Dielectric" "X7R" (at 163.83 102.87 0)
      (effects (font (size 1.27 1.27)) (justify left bottom) hide)
    )
    (property "Public" "False" (at 166.37 102.87 0)
      (effects (font (size 1.27 1.27)) (justify left bottom) hide)
    )
    (pin "1")
    (pin "2")
    (instances
      (project "ecp5-dc-scm"
        (path ""
          (reference "C13") (unit 1)
        )
      )
    )
  )

  (symbol (lib_id "antmicroCapacitors0402:C_10n_0402") (at 283.21 93.98 270) (mirror x) (unit 1)
    (in_bom yes) (on_board yes) (dnp no)
    (property "Reference" "C5" (at 283.21 88.9 90)
      (effects (font (size 1.524 1.524)) (justify left))
    )
    (property "Value" "C_10n_0402" (at 279.4 93.98 0)
      (effects (font (size 1.524 1.524)) hide)
    )
    (property "Footprint" "antmicro-footprints:C_0402_1005Metric" (at 288.29 88.9 0)
      (effects (font (size 1.524 1.524)) (justify left) hide)
    )
    (property "Datasheet" "https://www.murata.com/products/productdetail?partno=GRM155R71H103KA88%23" (at 283.21 93.98 0)
      (effects (font (size 1.27 1.27)) hide)
    )
    (property "Manufacturer" "Murata" (at 293.37 88.9 0)
      (effects (font (size 1.524 1.524)) (justify left) hide)
    )
    (property "MPN" "GRM155R71H103KA88D" (at 290.83 88.9 0)
      (effects (font (size 1.524 1.524)) (justify left) hide)
    )
    (property "Val" "10n" (at 283.21 93.98 90)
      (effects (font (size 1.27 1.27)) (justify left))
    )
    (property "License" "Apache-2.0" (at 260.35 73.66 0)
      (effects (font (size 1.27 1.27) (thickness 0.15)) (justify left bottom) hide)
    )
    (property "Author" "Antmicro" (at 257.81 73.66 0)
      (effects (font (size 1.27 1.27) (thickness 0.15)) (justify left bottom) hide)
    )
    (property "Voltage" "50V" (at 255.27 73.66 0)
      (effects (font (size 1.27 1.27)) (justify left bottom) hide)
    )
    (property "Dielectric" "X7R" (at 252.73 73.66 0)
      (effects (font (size 1.27 1.27)) (justify left bottom) hide)
    )
    (property "Public" "False" (at 250.19 73.66 0)
      (effects (font (size 1.27 1.27)) (justify left bottom) hide)
    )
    (pin "1")
    (pin "2")
    (instances
      (project "ecp5-dc-scm"
        (path ""
          (reference "C5") (unit 1)
        )
      )
    )
  )

  (symbol (lib_id "antmicroCapacitors0402:C_4u7_0402") (at 308.61 93.98 270) (mirror x) (unit 1)
    (in_bom yes) (on_board yes) (dnp no)
    (property "Reference" "C1" (at 309.88 88.9 90)
      (effects (font (size 1.524 1.524)) (justify left))
    )
    (property "Value" "C_4u7_0402" (at 304.8 93.98 0)
      (effects (font (size 1.524 1.524)) hide)
    )
    (property "Footprint" "antmicro-footprints:C_0402_1005Metric" (at 313.69 88.9 0)
      (effects (font (size 1.524 1.524)) (justify left) hide)
    )
    (property "Datasheet" "https://www.murata.com/products/productdetail?partno=GRM155R61A475MEAA%23" (at 308.61 93.98 0)
      (effects (font (size 1.27 1.27)) hide)
    )
    (property "Manufacturer" "Murata" (at 318.77 88.9 0)
      (effects (font (size 1.524 1.524)) (justify left) hide)
    )
    (property "MPN" "GRM155R61A475MEAAD" (at 316.23 88.9 0)
      (effects (font (size 1.524 1.524)) (justify left) hide)
    )
    (property "Val" "4u7" (at 309.88 93.98 90)
      (effects (font (size 1.27 1.27)) (justify left))
    )
    (property "License" "Apache-2.0" (at 285.75 73.66 0)
      (effects (font (size 1.27 1.27) (thickness 0.15)) (justify left bottom) hide)
    )
    (property "Author" "Antmicro" (at 283.21 73.66 0)
      (effects (font (size 1.27 1.27) (thickness 0.15)) (justify left bottom) hide)
    )
    (property "Voltage" "" (at 280.67 73.66 0)
      (effects (font (size 1.27 1.27)) (justify left bottom) hide)
    )
    (property "Dielectric" "" (at 278.13 73.66 0)
      (effects (font (size 1.27 1.27)) (justify left bottom) hide)
    )
    (property "Public" "False" (at 275.59 73.66 0)
      (effects (font (size 1.27 1.27)) (justify left bottom) hide)
    )
    (pin "1")
    (pin "2")
    (instances
      (project "ecp5-dc-scm"
        (path ""
          (reference "C1") (unit 1)
        )
      )
    )
  )

  (symbol (lib_id "antmicroCapacitors0402:C_470n_0402") (at 302.26 93.98 270) (mirror x) (unit 1)
    (in_bom yes) (on_board yes) (dnp no)
    (property "Reference" "C2" (at 306.07 88.9 90)
      (effects (font (size 1.524 1.524)) (justify right))
    )
    (property "Value" "C_470n_0402" (at 298.45 93.98 0)
      (effects (font (size 1.524 1.524)) hide)
    )
    (property "Footprint" "antmicro-footprints:C_0402_1005Metric" (at 307.34 88.9 0)
      (effects (font (size 1.524 1.524)) (justify left) hide)
    )
    (property "Datasheet" "https://product.tdk.com/en/search/capacitor/ceramic/mlcc/info?part_no=C1005X5R1E474M050BB" (at 302.26 93.98 0)
      (effects (font (size 1.27 1.27)) hide)
    )
    (property "Manufacturer" "TDK" (at 312.42 88.9 0)
      (effects (font (size 1.524 1.524)) (justify left) hide)
    )
    (property "MPN" "C1005X5R1E474M050BB" (at 309.88 88.9 0)
      (effects (font (size 1.524 1.524)) (justify left) hide)
    )
    (property "Val" "470n" (at 307.34 93.98 90)
      (effects (font (size 1.27 1.27)) (justify right))
    )
    (property "License" "Apache-2.0" (at 279.4 73.66 0)
      (effects (font (size 1.27 1.27) (thickness 0.15)) (justify left bottom) hide)
    )
    (property "Author" "Antmicro" (at 276.86 73.66 0)
      (effects (font (size 1.27 1.27) (thickness 0.15)) (justify left bottom) hide)
    )
    (property "Voltage" "" (at 274.32 73.66 0)
      (effects (font (size 1.27 1.27)) (justify left bottom) hide)
    )
    (property "Dielectric" "" (at 271.78 73.66 0)
      (effects (font (size 1.27 1.27)) (justify left bottom) hide)
    )
    (property "Public" "False" (at 269.24 73.66 0)
      (effects (font (size 1.27 1.27)) (justify left bottom) hide)
    )
    (pin "1")
    (pin "2")
    (instances
      (project "ecp5-dc-scm"
        (path ""
          (reference "C2") (unit 1)
        )
      )
    )
  )

  (symbol (lib_id "antmicroCapacitors0402:C_470n_0402") (at 295.91 93.98 270) (mirror x) (unit 1)
    (in_bom yes) (on_board yes) (dnp no)
    (property "Reference" "C3" (at 295.91 88.9 90)
      (effects (font (size 1.524 1.524)) (justify left))
    )
    (property "Value" "C_470n_0402" (at 292.1 93.98 0)
      (effects (font (size 1.524 1.524)) hide)
    )
    (property "Footprint" "antmicro-footprints:C_0402_1005Metric" (at 300.99 88.9 0)
      (effects (font (size 1.524 1.524)) (justify left) hide)
    )
    (property "Datasheet" "https://product.tdk.com/en/search/capacitor/ceramic/mlcc/info?part_no=C1005X5R1E474M050BB" (at 295.91 93.98 0)
      (effects (font (size 1.27 1.27)) hide)
    )
    (property "Manufacturer" "TDK" (at 306.07 88.9 0)
      (effects (font (size 1.524 1.524)) (justify left) hide)
    )
    (property "MPN" "C1005X5R1E474M050BB" (at 303.53 88.9 0)
      (effects (font (size 1.524 1.524)) (justify left) hide)
    )
    (property "Val" "470n" (at 295.91 93.98 90)
      (effects (font (size 1.27 1.27)) (justify left))
    )
    (property "License" "Apache-2.0" (at 273.05 73.66 0)
      (effects (font (size 1.27 1.27) (thickness 0.15)) (justify left bottom) hide)
    )
    (property "Author" "Antmicro" (at 270.51 73.66 0)
      (effects (font (size 1.27 1.27) (thickness 0.15)) (justify left bottom) hide)
    )
    (property "Voltage" "" (at 267.97 73.66 0)
      (effects (font (size 1.27 1.27)) (justify left bottom) hide)
    )
    (property "Dielectric" "" (at 265.43 73.66 0)
      (effects (font (size 1.27 1.27)) (justify left bottom) hide)
    )
    (property "Public" "False" (at 262.89 73.66 0)
      (effects (font (size 1.27 1.27)) (justify left bottom) hide)
    )
    (pin "1")
    (pin "2")
    (instances
      (project "ecp5-dc-scm"
        (path ""
          (reference "C3") (unit 1)
        )
      )
    )
  )

  (symbol (lib_id "antmicroCapacitors0402:C_470n_0402") (at 289.56 93.98 270) (mirror x) (unit 1)
    (in_bom yes) (on_board yes) (dnp no)
    (property "Reference" "C4" (at 289.56 88.9 90)
      (effects (font (size 1.524 1.524)) (justify left))
    )
    (property "Value" "C_470n_0402" (at 285.75 93.98 0)
      (effects (font (size 1.524 1.524)) hide)
    )
    (property "Footprint" "antmicro-footprints:C_0402_1005Metric" (at 294.64 88.9 0)
      (effects (font (size 1.524 1.524)) (justify left) hide)
    )
    (property "Datasheet" "https://product.tdk.com/en/search/capacitor/ceramic/mlcc/info?part_no=C1005X5R1E474M050BB" (at 289.56 93.98 0)
      (effects (font (size 1.27 1.27)) hide)
    )
    (property "Manufacturer" "TDK" (at 299.72 88.9 0)
      (effects (font (size 1.524 1.524)) (justify left) hide)
    )
    (property "MPN" "C1005X5R1E474M050BB" (at 297.18 88.9 0)
      (effects (font (size 1.524 1.524)) (justify left) hide)
    )
    (property "Val" "470n" (at 289.56 93.98 90)
      (effects (font (size 1.27 1.27)) (justify left))
    )
    (property "License" "Apache-2.0" (at 266.7 73.66 0)
      (effects (font (size 1.27 1.27) (thickness 0.15)) (justify left bottom) hide)
    )
    (property "Author" "Antmicro" (at 264.16 73.66 0)
      (effects (font (size 1.27 1.27) (thickness 0.15)) (justify left bottom) hide)
    )
    (property "Voltage" "" (at 261.62 73.66 0)
      (effects (font (size 1.27 1.27)) (justify left bottom) hide)
    )
    (property "Dielectric" "" (at 259.08 73.66 0)
      (effects (font (size 1.27 1.27)) (justify left bottom) hide)
    )
    (property "Public" "False" (at 256.54 73.66 0)
      (effects (font (size 1.27 1.27)) (justify left bottom) hide)
    )
    (pin "1")
    (pin "2")
    (instances
      (project "ecp5-dc-scm"
        (path ""
          (reference "C4") (unit 1)
        )
      )
    )
  )

  (symbol (lib_id "antmicroCapacitors0402:C_10n_0402") (at 139.7 123.19 90) (unit 1)
    (in_bom yes) (on_board yes) (dnp no)
    (property "Reference" "C16" (at 140.97 119.38 90)
      (effects (font (size 1.524 1.524)) (justify right))
    )
    (property "Value" "C_10n_0402" (at 143.51 123.19 0)
      (effects (font (size 1.524 1.524)) hide)
    )
    (property "Footprint" "antmicro-footprints:C_0402_1005Metric" (at 134.62 118.11 0)
      (effects (font (size 1.524 1.524)) (justify left) hide)
    )
    (property "Datasheet" "https://www.murata.com/products/productdetail?partno=GRM155R71H103KA88%23" (at 139.7 123.19 0)
      (effects (font (size 1.27 1.27)) hide)
    )
    (property "Manufacturer" "Murata" (at 129.54 118.11 0)
      (effects (font (size 1.524 1.524)) (justify left) hide)
    )
    (property "MPN" "GRM155R71H103KA88D" (at 132.08 118.11 0)
      (effects (font (size 1.524 1.524)) (justify left) hide)
    )
    (property "Val" "10n" (at 140.97 121.92 90)
      (effects (font (size 1.27 1.27)) (justify right))
    )
    (property "License" "Apache-2.0" (at 162.56 102.87 0)
      (effects (font (size 1.27 1.27) (thickness 0.15)) (justify left bottom) hide)
    )
    (property "Author" "Antmicro" (at 165.1 102.87 0)
      (effects (font (size 1.27 1.27) (thickness 0.15)) (justify left bottom) hide)
    )
    (property "Voltage" "50V" (at 167.64 102.87 0)
      (effects (font (size 1.27 1.27)) (justify left bottom) hide)
    )
    (property "Dielectric" "X7R" (at 170.18 102.87 0)
      (effects (font (size 1.27 1.27)) (justify left bottom) hide)
    )
    (property "Public" "False" (at 172.72 102.87 0)
      (effects (font (size 1.27 1.27)) (justify left bottom) hide)
    )
    (pin "1")
    (pin "2")
    (instances
      (project "ecp5-dc-scm"
        (path ""
          (reference "C16") (unit 1)
        )
      )
    )
  )

  (symbol (lib_id "antmicroCapacitors0402:C_4u7_0402") (at 125.73 123.19 90) (unit 1)
    (in_bom yes) (on_board yes) (dnp no) (fields_autoplaced)
    (property "Reference" "C10" (at 123.19 119.3736 90)
      (effects (font (size 1.524 1.524)) (justify left))
    )
    (property "Value" "C_4u7_0402" (at 129.54 123.19 0)
      (effects (font (size 1.524 1.524)) hide)
    )
    (property "Footprint" "antmicro-footprints:C_0402_1005Metric" (at 120.65 118.11 0)
      (effects (font (size 1.524 1.524)) (justify left) hide)
    )
    (property "Datasheet" "https://www.murata.com/products/productdetail?partno=GRM155R61A475MEAA%23" (at 125.73 123.19 0)
      (effects (font (size 1.27 1.27)) hide)
    )
    (property "Manufacturer" "Murata" (at 115.57 118.11 0)
      (effects (font (size 1.524 1.524)) (justify left) hide)
    )
    (property "MPN" "GRM155R61A475MEAAD" (at 118.11 118.11 0)
      (effects (font (size 1.524 1.524)) (justify left) hide)
    )
    (property "Val" "4u7" (at 123.19 121.9136 90)
      (effects (font (size 1.27 1.27)) (justify left))
    )
    (property "License" "Apache-2.0" (at 148.59 102.87 0)
      (effects (font (size 1.27 1.27) (thickness 0.15)) (justify left bottom) hide)
    )
    (property "Author" "Antmicro" (at 151.13 102.87 0)
      (effects (font (size 1.27 1.27) (thickness 0.15)) (justify left bottom) hide)
    )
    (property "Voltage" "" (at 153.67 102.87 0)
      (effects (font (size 1.27 1.27)) (justify left bottom) hide)
    )
    (property "Dielectric" "" (at 156.21 102.87 0)
      (effects (font (size 1.27 1.27)) (justify left bottom) hide)
    )
    (property "Public" "False" (at 158.75 102.87 0)
      (effects (font (size 1.27 1.27)) (justify left bottom) hide)
    )
    (pin "1")
    (pin "2")
    (instances
      (project "ecp5-dc-scm"
        (path ""
          (reference "C10") (unit 1)
        )
      )
    )
  )

  (symbol (lib_id "antmicroCapacitors0402:C_4u7_0402") (at 110.49 100.33 90) (unit 1)
    (in_bom yes) (on_board yes) (dnp no) (fields_autoplaced)
    (property "Reference" "C6" (at 109.22 96.5136 90)
      (effects (font (size 1.524 1.524)) (justify left))
    )
    (property "Value" "C_4u7_0402" (at 114.3 100.33 0)
      (effects (font (size 1.524 1.524)) hide)
    )
    (property "Footprint" "antmicro-footprints:C_0402_1005Metric" (at 105.41 95.25 0)
      (effects (font (size 1.524 1.524)) (justify left) hide)
    )
    (property "Datasheet" "https://www.murata.com/products/productdetail?partno=GRM155R61A475MEAA%23" (at 110.49 100.33 0)
      (effects (font (size 1.27 1.27)) hide)
    )
    (property "Manufacturer" "Murata" (at 100.33 95.25 0)
      (effects (font (size 1.524 1.524)) (justify left) hide)
    )
    (property "MPN" "GRM155R61A475MEAAD" (at 102.87 95.25 0)
      (effects (font (size 1.524 1.524)) (justify left) hide)
    )
    (property "Val" "4u7" (at 109.22 99.0536 90)
      (effects (font (size 1.27 1.27)) (justify left))
    )
    (property "License" "Apache-2.0" (at 133.35 80.01 0)
      (effects (font (size 1.27 1.27) (thickness 0.15)) (justify left bottom) hide)
    )
    (property "Author" "Antmicro" (at 135.89 80.01 0)
      (effects (font (size 1.27 1.27) (thickness 0.15)) (justify left bottom) hide)
    )
    (property "Voltage" "" (at 138.43 80.01 0)
      (effects (font (size 1.27 1.27)) (justify left bottom) hide)
    )
    (property "Dielectric" "" (at 140.97 80.01 0)
      (effects (font (size 1.27 1.27)) (justify left bottom) hide)
    )
    (property "Public" "False" (at 143.51 80.01 0)
      (effects (font (size 1.27 1.27)) (justify left bottom) hide)
    )
    (pin "1")
    (pin "2")
    (instances
      (project "ecp5-dc-scm"
        (path ""
          (reference "C6") (unit 1)
        )
      )
    )
  )

  (symbol (lib_id "antmicroCapacitors0402:C_470n_0402") (at 118.11 100.33 90) (unit 1)
    (in_bom yes) (on_board yes) (dnp no)
    (property "Reference" "C8" (at 113.03 96.52 90)
      (effects (font (size 1.524 1.524)) (justify right))
    )
    (property "Value" "C_470n_0402" (at 121.92 100.33 0)
      (effects (font (size 1.524 1.524)) hide)
    )
    (property "Footprint" "antmicro-footprints:C_0402_1005Metric" (at 113.03 95.25 0)
      (effects (font (size 1.524 1.524)) (justify left) hide)
    )
    (property "Datasheet" "https://product.tdk.com/en/search/capacitor/ceramic/mlcc/info?part_no=C1005X5R1E474M050BB" (at 118.11 100.33 0)
      (effects (font (size 1.27 1.27)) hide)
    )
    (property "Manufacturer" "TDK" (at 107.95 95.25 0)
      (effects (font (size 1.524 1.524)) (justify left) hide)
    )
    (property "MPN" "C1005X5R1E474M050BB" (at 110.49 95.25 0)
      (effects (font (size 1.524 1.524)) (justify left) hide)
    )
    (property "Val" "470n" (at 113.03 99.06 90)
      (effects (font (size 1.27 1.27)) (justify right))
    )
    (property "License" "Apache-2.0" (at 140.97 80.01 0)
      (effects (font (size 1.27 1.27) (thickness 0.15)) (justify left bottom) hide)
    )
    (property "Author" "Antmicro" (at 143.51 80.01 0)
      (effects (font (size 1.27 1.27) (thickness 0.15)) (justify left bottom) hide)
    )
    (property "Voltage" "" (at 146.05 80.01 0)
      (effects (font (size 1.27 1.27)) (justify left bottom) hide)
    )
    (property "Dielectric" "" (at 148.59 80.01 0)
      (effects (font (size 1.27 1.27)) (justify left bottom) hide)
    )
    (property "Public" "False" (at 151.13 80.01 0)
      (effects (font (size 1.27 1.27)) (justify left bottom) hide)
    )
    (pin "1")
    (pin "2")
    (instances
      (project "ecp5-dc-scm"
        (path ""
          (reference "C8") (unit 1)
        )
      )
    )
  )

  (symbol (lib_id "antmicroCapacitors0402:C_10n_0402") (at 133.35 100.33 90) (unit 1)
    (in_bom yes) (on_board yes) (dnp no)
    (property "Reference" "C14" (at 127 96.52 90)
      (effects (font (size 1.524 1.524)) (justify right))
    )
    (property "Value" "C_10n_0402" (at 137.16 100.33 0)
      (effects (font (size 1.524 1.524)) hide)
    )
    (property "Footprint" "antmicro-footprints:C_0402_1005Metric" (at 128.27 95.25 0)
      (effects (font (size 1.524 1.524)) (justify left) hide)
    )
    (property "Datasheet" "https://www.murata.com/products/productdetail?partno=GRM155R71H103KA88%23" (at 133.35 100.33 0)
      (effects (font (size 1.27 1.27)) hide)
    )
    (property "Manufacturer" "Murata" (at 123.19 95.25 0)
      (effects (font (size 1.524 1.524)) (justify left) hide)
    )
    (property "MPN" "GRM155R71H103KA88D" (at 125.73 95.25 0)
      (effects (font (size 1.524 1.524)) (justify left) hide)
    )
    (property "Val" "10n" (at 128.27 99.06 90)
      (effects (font (size 1.27 1.27)) (justify right))
    )
    (property "License" "Apache-2.0" (at 156.21 80.01 0)
      (effects (font (size 1.27 1.27) (thickness 0.15)) (justify left bottom) hide)
    )
    (property "Author" "Antmicro" (at 158.75 80.01 0)
      (effects (font (size 1.27 1.27) (thickness 0.15)) (justify left bottom) hide)
    )
    (property "Voltage" "50V" (at 161.29 80.01 0)
      (effects (font (size 1.27 1.27)) (justify left bottom) hide)
    )
    (property "Dielectric" "X7R" (at 163.83 80.01 0)
      (effects (font (size 1.27 1.27)) (justify left bottom) hide)
    )
    (property "Public" "False" (at 166.37 80.01 0)
      (effects (font (size 1.27 1.27)) (justify left bottom) hide)
    )
    (pin "1")
    (pin "2")
    (instances
      (project "ecp5-dc-scm"
        (path ""
          (reference "C14") (unit 1)
        )
      )
    )
  )

  (symbol (lib_id "antmicroCapacitors0402:C_10n_0402") (at 140.97 100.33 90) (unit 1)
    (in_bom yes) (on_board yes) (dnp no)
    (property "Reference" "C17" (at 134.62 96.52 90)
      (effects (font (size 1.524 1.524)) (justify right))
    )
    (property "Value" "C_10n_0402" (at 144.78 100.33 0)
      (effects (font (size 1.524 1.524)) hide)
    )
    (property "Footprint" "antmicro-footprints:C_0402_1005Metric" (at 135.89 95.25 0)
      (effects (font (size 1.524 1.524)) (justify left) hide)
    )
    (property "Datasheet" "https://www.murata.com/products/productdetail?partno=GRM155R71H103KA88%23" (at 140.97 100.33 0)
      (effects (font (size 1.27 1.27)) hide)
    )
    (property "Manufacturer" "Murata" (at 130.81 95.25 0)
      (effects (font (size 1.524 1.524)) (justify left) hide)
    )
    (property "MPN" "GRM155R71H103KA88D" (at 133.35 95.25 0)
      (effects (font (size 1.524 1.524)) (justify left) hide)
    )
    (property "Val" "10n" (at 135.89 99.06 90)
      (effects (font (size 1.27 1.27)) (justify right))
    )
    (property "License" "Apache-2.0" (at 163.83 80.01 0)
      (effects (font (size 1.27 1.27) (thickness 0.15)) (justify left bottom) hide)
    )
    (property "Author" "Antmicro" (at 166.37 80.01 0)
      (effects (font (size 1.27 1.27) (thickness 0.15)) (justify left bottom) hide)
    )
    (property "Voltage" "50V" (at 168.91 80.01 0)
      (effects (font (size 1.27 1.27)) (justify left bottom) hide)
    )
    (property "Dielectric" "X7R" (at 171.45 80.01 0)
      (effects (font (size 1.27 1.27)) (justify left bottom) hide)
    )
    (property "Public" "False" (at 173.99 80.01 0)
      (effects (font (size 1.27 1.27)) (justify left bottom) hide)
    )
    (pin "1")
    (pin "2")
    (instances
      (project "ecp5-dc-scm"
        (path ""
          (reference "C17") (unit 1)
        )
      )
    )
  )

  (symbol (lib_id "antmicroCapacitors0402:C_10n_0402") (at 125.73 100.33 90) (unit 1)
    (in_bom yes) (on_board yes) (dnp no) (fields_autoplaced)
    (property "Reference" "C11" (at 124.46 96.5136 90)
      (effects (font (size 1.524 1.524)) (justify left))
    )
    (property "Value" "C_10n_0402" (at 129.54 100.33 0)
      (effects (font (size 1.524 1.524)) hide)
    )
    (property "Footprint" "antmicro-footprints:C_0402_1005Metric" (at 120.65 95.25 0)
      (effects (font (size 1.524 1.524)) (justify left) hide)
    )
    (property "Datasheet" "https://www.murata.com/products/productdetail?partno=GRM155R71H103KA88%23" (at 125.73 100.33 0)
      (effects (font (size 1.27 1.27)) hide)
    )
    (property "Manufacturer" "Murata" (at 115.57 95.25 0)
      (effects (font (size 1.524 1.524)) (justify left) hide)
    )
    (property "MPN" "GRM155R71H103KA88D" (at 118.11 95.25 0)
      (effects (font (size 1.524 1.524)) (justify left) hide)
    )
    (property "Val" "10n" (at 124.46 99.0536 90)
      (effects (font (size 1.27 1.27)) (justify left))
    )
    (property "License" "Apache-2.0" (at 148.59 80.01 0)
      (effects (font (size 1.27 1.27) (thickness 0.15)) (justify left bottom) hide)
    )
    (property "Author" "Antmicro" (at 151.13 80.01 0)
      (effects (font (size 1.27 1.27) (thickness 0.15)) (justify left bottom) hide)
    )
    (property "Voltage" "50V" (at 153.67 80.01 0)
      (effects (font (size 1.27 1.27)) (justify left bottom) hide)
    )
    (property "Dielectric" "X7R" (at 156.21 80.01 0)
      (effects (font (size 1.27 1.27)) (justify left bottom) hide)
    )
    (property "Public" "False" (at 158.75 80.01 0)
      (effects (font (size 1.27 1.27)) (justify left bottom) hide)
    )
    (pin "1")
    (pin "2")
    (instances
      (project "ecp5-dc-scm"
        (path ""
          (reference "C11") (unit 1)
        )
      )
    )
  )

  (symbol (lib_id "antmicropower:GND") (at 125.73 127 0) (unit 1)
    (in_bom yes) (on_board yes) (dnp no)
    (property "Reference" "#PWR03" (at 125.73 133.35 0)
      (effects (font (size 1.27 1.27)) hide)
    )
    (property "Value" "GND" (at 123.825 130.81 0)
      (effects (font (size 1.27 1.27)) (justify left))
    )
    (property "Footprint" "" (at 125.73 127 0)
      (effects (font (size 1.27 1.27)) hide)
    )
    (property "Datasheet" "" (at 125.73 127 0)
      (effects (font (size 1.27 1.27)) hide)
    )
    (property "Author" "Antmicro" (at 134.62 134.62 0)
      (effects (font (size 1.27 1.27) (thickness 0.15)) (justify left bottom) hide)
    )
    (property "License" "Apache-2.0" (at 134.62 137.16 0)
      (effects (font (size 1.27 1.27) (thickness 0.15)) (justify left bottom) hide)
    )
    (pin "1")
    (instances
      (project "ecp5-dc-scm"
        (path ""
          (reference "#PWR03") (unit 1)
        )
      )
    )
  )

  (symbol (lib_id "antmicropower:GND") (at 110.49 104.14 0) (unit 1)
    (in_bom yes) (on_board yes) (dnp no)
    (property "Reference" "#PWR02" (at 110.49 110.49 0)
      (effects (font (size 1.27 1.27)) hide)
    )
    (property "Value" "GND" (at 110.617 108.5342 0)
      (effects (font (size 1.27 1.27)))
    )
    (property "Footprint" "" (at 110.49 104.14 0)
      (effects (font (size 1.27 1.27)) hide)
    )
    (property "Datasheet" "" (at 110.49 104.14 0)
      (effects (font (size 1.27 1.27)) hide)
    )
    (property "Author" "Antmicro" (at 119.38 111.76 0)
      (effects (font (size 1.27 1.27) (thickness 0.15)) (justify left bottom) hide)
    )
    (property "License" "Apache-2.0" (at 119.38 114.3 0)
      (effects (font (size 1.27 1.27) (thickness 0.15)) (justify left bottom) hide)
    )
    (pin "1")
    (instances
      (project "ecp5-dc-scm"
        (path ""
          (reference "#PWR02") (unit 1)
        )
      )
    )
  )

  (symbol (lib_id "antmicroCapacitors0402:C_100n_0402") (at 116.84 140.97 270) (unit 1)
    (in_bom yes) (on_board yes) (dnp no) (fields_autoplaced)
    (property "Reference" "C47" (at 119.38 142.2463 90)
      (effects (font (size 1.524 1.524)) (justify left))
    )
    (property "Value" "C_100n_0402" (at 113.03 140.97 0)
      (effects (font (size 1.524 1.524)) hide)
    )
    (property "Footprint" "antmicro-footprints:C_0402_1005Metric" (at 121.92 146.05 0)
      (effects (font (size 1.524 1.524)) (justify left) hide)
    )
    (property "Datasheet" "https://www.murata.com/products/productdetail?partno=GRM155R61H104KE14%23" (at 116.84 140.97 0)
      (effects (font (size 1.27 1.27)) hide)
    )
    (property "Manufacturer" "Murata" (at 127 146.05 0)
      (effects (font (size 1.524 1.524)) (justify left) hide)
    )
    (property "MPN" "GRM155R61H104KE14D" (at 124.46 146.05 0)
      (effects (font (size 1.524 1.524)) (justify left) hide)
    )
    (property "Val" "100n" (at 119.38 144.7863 90)
      (effects (font (size 1.27 1.27)) (justify left))
    )
    (property "License" "Apache-2.0" (at 93.98 161.29 0)
      (effects (font (size 1.27 1.27) (thickness 0.15)) (justify left bottom) hide)
    )
    (property "Author" "Antmicro" (at 91.44 161.29 0)
      (effects (font (size 1.27 1.27) (thickness 0.15)) (justify left bottom) hide)
    )
    (property "Voltage" "50V" (at 88.9 161.29 0)
      (effects (font (size 1.27 1.27)) (justify left bottom) hide)
    )
    (property "Dielectric" "X5R" (at 86.36 161.29 0)
      (effects (font (size 1.27 1.27)) (justify left bottom) hide)
    )
    (property "Public" "False" (at 83.82 161.29 0)
      (effects (font (size 1.27 1.27)) (justify left bottom) hide)
    )
    (pin "1")
    (pin "2")
    (instances
      (project "ecp5-dc-scm"
        (path ""
          (reference "C47") (unit 1)
        )
      )
    )
  )

  (symbol (lib_id "antmicropower:GND") (at 308.61 99.06 0) (mirror y) (unit 1)
    (in_bom yes) (on_board yes) (dnp no)
    (property "Reference" "#PWR01" (at 308.61 105.41 0)
      (effects (font (size 1.27 1.27)) hide)
    )
    (property "Value" "GND" (at 308.483 103.4542 0)
      (effects (font (size 1.27 1.27)))
    )
    (property "Footprint" "" (at 308.61 99.06 0)
      (effects (font (size 1.27 1.27)) hide)
    )
    (property "Datasheet" "" (at 308.61 99.06 0)
      (effects (font (size 1.27 1.27)) hide)
    )
    (property "Author" "Antmicro" (at 299.72 106.68 0)
      (effects (font (size 1.27 1.27) (thickness 0.15)) (justify left bottom) hide)
    )
    (property "License" "Apache-2.0" (at 299.72 109.22 0)
      (effects (font (size 1.27 1.27) (thickness 0.15)) (justify left bottom) hide)
    )
    (pin "1")
    (instances
      (project "ecp5-dc-scm"
        (path ""
          (reference "#PWR01") (unit 1)
        )
      )
    )
  )

  (symbol (lib_id "antmicropower:GND") (at 116.84 147.32 0) (unit 1)
    (in_bom yes) (on_board yes) (dnp no)
    (property "Reference" "#PWR010" (at 116.84 153.67 0)
      (effects (font (size 1.27 1.27)) hide)
    )
    (property "Value" "GND" (at 116.967 151.7142 0)
      (effects (font (size 1.27 1.27)))
    )
    (property "Footprint" "" (at 116.84 147.32 0)
      (effects (font (size 1.27 1.27)) hide)
    )
    (property "Datasheet" "" (at 116.84 147.32 0)
      (effects (font (size 1.27 1.27)) hide)
    )
    (property "Author" "Antmicro" (at 125.73 154.94 0)
      (effects (font (size 1.27 1.27) (thickness 0.15)) (justify left bottom) hide)
    )
    (property "License" "Apache-2.0" (at 125.73 157.48 0)
      (effects (font (size 1.27 1.27) (thickness 0.15)) (justify left bottom) hide)
    )
    (pin "1")
    (instances
      (project "ecp5-dc-scm"
        (path ""
          (reference "#PWR010") (unit 1)
        )
      )
    )
  )

  (symbol (lib_id "antmicroResistors0402:R_4k7_0402") (at 116.84 133.35 270) (unit 1)
    (in_bom yes) (on_board yes) (dnp no) (fields_autoplaced)
    (property "Reference" "R48" (at 119.38 134.62 90)
      (effects (font (size 1.524 1.524)) (justify left))
    )
    (property "Value" "R_4k7_0402" (at 113.03 133.35 0)
      (effects (font (size 1.524 1.524)) hide)
    )
    (property "Footprint" "antmicro-footprints:R_0402_1005Metric" (at 121.92 138.43 0)
      (effects (font (size 1.524 1.524)) (justify left) hide)
    )
    (property "Datasheet" "https://www.bourns.com/docs/product-datasheets/cr.pdf" (at 116.84 133.35 0)
      (effects (font (size 1.27 1.27)) hide)
    )
    (property "Manufacturer" "Bourns" (at 127 138.43 0)
      (effects (font (size 1.524 1.524)) (justify left) hide)
    )
    (property "MPN" "CR0402-FX-4701GLF" (at 124.46 138.43 0)
      (effects (font (size 1.524 1.524)) (justify left) hide)
    )
    (property "Val" "4k7" (at 119.38 137.16 90)
      (effects (font (size 1.27 1.27)) (justify left))
    )
    (property "License" "Apache-2.0" (at 91.44 153.67 0)
      (effects (font (size 1.27 1.27) (thickness 0.15)) (justify left bottom) hide)
    )
    (property "Author" "Antmicro" (at 88.9 153.67 0)
      (effects (font (size 1.27 1.27) (thickness 0.15)) (justify left bottom) hide)
    )
    (property "Tolerance" "1%" (at 106.68 153.67 0)
      (effects (font (size 1.27 1.27)) (justify left bottom) hide)
    )
    (property "Public" "False" (at 86.36 153.67 0)
      (effects (font (size 1.27 1.27)) (justify left bottom) hide)
    )
    (pin "1")
    (pin "2")
    (instances
      (project "ecp5-dc-scm"
        (path ""
          (reference "R48") (unit 1)
        )
      )
    )
  )

  (symbol (lib_id "antmicroFerriteBeadsandChips:FB_120Z_2A_Murata-BLM18PG_0603") (at 299.72 107.95 0) (unit 1)
    (in_bom yes) (on_board yes) (dnp no)
    (property "Reference" "FB2" (at 298.45 106.68 0)
      (effects (font (size 1.524 1.524)))
    )
    (property "Value" "FB_120Z_2A_Murata-BLM18PG_0603" (at 299.72 103.3526 0)
      (effects (font (size 1.524 1.524)) hide)
    )
    (property "Footprint" "antmicro-footprints:FB_0603_1608Metric" (at 304.8 102.87 0)
      (effects (font (size 1.524 1.524)) (justify left) hide)
    )
    (property "Datasheet" "https://www.murata.com/en-us/products/productdata/8796738650142/ENFA0003.pdf" (at 304.8 100.33 0)
      (effects (font (size 1.524 1.524)) (justify left) hide)
    )
    (property "MPN" "BLM18PG121SN1D" (at 304.8 95.25 0)
      (effects (font (size 1.524 1.524)) (justify left) hide)
    )
    (property "Manufacturer" "Murata" (at 304.8 80.01 0)
      (effects (font (size 1.524 1.524)) (justify left) hide)
    )
    (property "Val" "120Z/2A" (at 298.45 111.76 0)
      (effects (font (size 1.27 1.27)) (justify left bottom))
    )
    (property "Current" "" (at 320.04 130.81 0)
      (effects (font (size 1.27 1.27) (thickness 0.15)) (justify left bottom) hide)
    )
    (property "Author" "Antmicro" (at 314.96 125.73 0)
      (effects (font (size 1.27 1.27) (thickness 0.15)) (justify left bottom) hide)
    )
    (property "License" "Apache-2.0" (at 314.96 128.27 0)
      (effects (font (size 1.27 1.27) (thickness 0.15)) (justify left bottom) hide)
    )
    (property "Public" "False" (at 320.04 123.19 0)
      (effects (font (size 1.27 1.27)) (justify left bottom) hide)
    )
    (pin "1")
    (pin "2")
    (instances
      (project "ecp5-dc-scm"
        (path ""
          (reference "FB2") (unit 1)
        )
      )
    )
  )

  (symbol (lib_id "antmicroFerriteBeadsandChips:FB_120Z_2A_Murata-BLM18PG_0603") (at 302.26 130.81 0) (unit 1)
    (in_bom yes) (on_board yes) (dnp no)
    (property "Reference" "FB3" (at 300.99 129.54 0)
      (effects (font (size 1.524 1.524)))
    )
    (property "Value" "FB_120Z_2A_Murata-BLM18PG_0603" (at 302.26 126.2126 0)
      (effects (font (size 1.524 1.524)) hide)
    )
    (property "Footprint" "antmicro-footprints:FB_0603_1608Metric" (at 307.34 125.73 0)
      (effects (font (size 1.524 1.524)) (justify left) hide)
    )
    (property "Datasheet" "https://www.murata.com/en-us/products/productdata/8796738650142/ENFA0003.pdf" (at 307.34 123.19 0)
      (effects (font (size 1.524 1.524)) (justify left) hide)
    )
    (property "MPN" "BLM18PG121SN1D" (at 307.34 118.11 0)
      (effects (font (size 1.524 1.524)) (justify left) hide)
    )
    (property "Manufacturer" "Murata" (at 307.34 102.87 0)
      (effects (font (size 1.524 1.524)) (justify left) hide)
    )
    (property "Val" "120Z/2A" (at 300.99 134.62 0)
      (effects (font (size 1.27 1.27)) (justify left bottom))
    )
    (property "Current" "" (at 322.58 153.67 0)
      (effects (font (size 1.27 1.27) (thickness 0.15)) (justify left bottom) hide)
    )
    (property "Author" "Antmicro" (at 317.5 148.59 0)
      (effects (font (size 1.27 1.27) (thickness 0.15)) (justify left bottom) hide)
    )
    (property "License" "Apache-2.0" (at 317.5 151.13 0)
      (effects (font (size 1.27 1.27) (thickness 0.15)) (justify left bottom) hide)
    )
    (property "Public" "False" (at 322.58 146.05 0)
      (effects (font (size 1.27 1.27)) (justify left bottom) hide)
    )
    (pin "1")
    (pin "2")
    (instances
      (project "ecp5-dc-scm"
        (path ""
          (reference "FB3") (unit 1)
        )
      )
    )
  )

  (symbol (lib_id "antmicroFerriteBeadsandChips:FB_120Z_2A_Murata-BLM18PG_0603") (at 107.95 115.57 0) (unit 1)
    (in_bom yes) (on_board yes) (dnp no)
    (property "Reference" "FB1" (at 105.41 114.3 0)
      (effects (font (size 1.524 1.524)))
    )
    (property "Value" "FB_120Z_2A_Murata-BLM18PG_0603" (at 110.4519 109.22 0)
      (effects (font (size 1.524 1.524)) hide)
    )
    (property "Footprint" "antmicro-footprints:FB_0603_1608Metric" (at 113.03 110.49 0)
      (effects (font (size 1.524 1.524)) (justify left) hide)
    )
    (property "Datasheet" "https://www.murata.com/en-us/products/productdata/8796738650142/ENFA0003.pdf" (at 113.03 107.95 0)
      (effects (font (size 1.524 1.524)) (justify left) hide)
    )
    (property "MPN" "BLM18PG121SN1D" (at 113.03 102.87 0)
      (effects (font (size 1.524 1.524)) (justify left) hide)
    )
    (property "Manufacturer" "Murata" (at 113.03 87.63 0)
      (effects (font (size 1.524 1.524)) (justify left) hide)
    )
    (property "Val" "120Z/2A" (at 118.11 114.3 0)
      (effects (font (size 1.27 1.27)))
    )
    (property "Current" "" (at 128.27 138.43 0)
      (effects (font (size 1.27 1.27) (thickness 0.15)) (justify left bottom) hide)
    )
    (property "Author" "Antmicro" (at 123.19 133.35 0)
      (effects (font (size 1.27 1.27) (thickness 0.15)) (justify left bottom) hide)
    )
    (property "License" "Apache-2.0" (at 123.19 135.89 0)
      (effects (font (size 1.27 1.27) (thickness 0.15)) (justify left bottom) hide)
    )
    (property "Public" "False" (at 128.27 130.81 0)
      (effects (font (size 1.27 1.27)) (justify left bottom) hide)
    )
    (pin "1")
    (pin "2")
    (instances
      (project "ecp5-dc-scm"
        (path ""
          (reference "FB1") (unit 1)
        )
      )
    )
  )

  (symbol (lib_id "antmicroResistors0402:R_12k1_0402") (at 231.14 167.64 90) (unit 1)
    (in_bom yes) (on_board yes) (dnp no) (fields_autoplaced)
    (property "Reference" "R13" (at 233.68 163.83 90)
      (effects (font (size 1.524 1.524)) (justify right))
    )
    (property "Value" "R_12k1_0402" (at 234.95 167.64 0)
      (effects (font (size 1.524 1.524)) hide)
    )
    (property "Footprint" "antmicro-footprints:R_0402_1005Metric" (at 226.06 162.56 0)
      (effects (font (size 1.524 1.524)) (justify left) hide)
    )
    (property "Datasheet" "https://www.bourns.com/docs/product-datasheets/cr.pdf" (at 231.14 167.64 0)
      (effects (font (size 1.27 1.27)) hide)
    )
    (property "Manufacturer" "Bourns" (at 220.98 162.56 0)
      (effects (font (size 1.524 1.524)) (justify left) hide)
    )
    (property "MPN" "CR0402-FX-1212GLF" (at 223.52 162.56 0)
      (effects (font (size 1.524 1.524)) (justify left) hide)
    )
    (property "Val" "12k1" (at 233.68 166.37 90)
      (effects (font (size 1.27 1.27)) (justify right))
    )
    (property "License" "Apache-2.0" (at 256.54 147.32 0)
      (effects (font (size 1.27 1.27) (thickness 0.15)) (justify left bottom) hide)
    )
    (property "Author" "Antmicro" (at 259.08 147.32 0)
      (effects (font (size 1.27 1.27) (thickness 0.15)) (justify left bottom) hide)
    )
    (property "Tolerance" "1%" (at 241.3 147.32 0)
      (effects (font (size 1.27 1.27)) (justify left bottom) hide)
    )
    (property "Public" "False" (at 261.62 147.32 0)
      (effects (font (size 1.27 1.27)) (justify left bottom) hide)
    )
    (pin "1")
    (pin "2")
    (instances
      (project "ecp5-dc-scm"
        (path ""
          (reference "R13") (unit 1)
        )
      )
    )
  )

  (symbol (lib_id "antmicroCapacitors0402:C_100n_0402") (at 349.25 163.83 90) (unit 1)
    (in_bom yes) (on_board yes) (dnp no) (fields_autoplaced)
    (property "Reference" "C30" (at 351.79 160.0136 90)
      (effects (font (size 1.524 1.524)) (justify right))
    )
    (property "Value" "C_100n_0402" (at 353.06 163.83 0)
      (effects (font (size 1.524 1.524)) hide)
    )
    (property "Footprint" "antmicro-footprints:C_0402_1005Metric" (at 344.17 158.75 0)
      (effects (font (size 1.524 1.524)) (justify left) hide)
    )
    (property "Datasheet" "https://www.murata.com/products/productdetail?partno=GRM155R61H104KE14%23" (at 349.25 163.83 0)
      (effects (font (size 1.27 1.27)) hide)
    )
    (property "Manufacturer" "Murata" (at 339.09 158.75 0)
      (effects (font (size 1.524 1.524)) (justify left) hide)
    )
    (property "MPN" "GRM155R61H104KE14D" (at 341.63 158.75 0)
      (effects (font (size 1.524 1.524)) (justify left) hide)
    )
    (property "Val" "100n" (at 351.79 162.5536 90)
      (effects (font (size 1.27 1.27)) (justify right))
    )
    (property "License" "Apache-2.0" (at 372.11 143.51 0)
      (effects (font (size 1.27 1.27) (thickness 0.15)) (justify left bottom) hide)
    )
    (property "Author" "Antmicro" (at 374.65 143.51 0)
      (effects (font (size 1.27 1.27) (thickness 0.15)) (justify left bottom) hide)
    )
    (property "Voltage" "50V" (at 377.19 143.51 0)
      (effects (font (size 1.27 1.27)) (justify left bottom) hide)
    )
    (property "Dielectric" "X5R" (at 379.73 143.51 0)
      (effects (font (size 1.27 1.27)) (justify left bottom) hide)
    )
    (property "Public" "False" (at 382.27 143.51 0)
      (effects (font (size 1.27 1.27)) (justify left bottom) hide)
    )
    (pin "1")
    (pin "2")
    (instances
      (project "ecp5-dc-scm"
        (path ""
          (reference "C30") (unit 1)
        )
      )
    )
  )

  (symbol (lib_id "antmicroCapacitors0402:C_100n_0402") (at 340.36 163.83 90) (unit 1)
    (in_bom yes) (on_board yes) (dnp no) (fields_autoplaced)
    (property "Reference" "C29" (at 342.9 160.0136 90)
      (effects (font (size 1.524 1.524)) (justify right))
    )
    (property "Value" "C_100n_0402" (at 344.17 163.83 0)
      (effects (font (size 1.524 1.524)) hide)
    )
    (property "Footprint" "antmicro-footprints:C_0402_1005Metric" (at 335.28 158.75 0)
      (effects (font (size 1.524 1.524)) (justify left) hide)
    )
    (property "Datasheet" "https://www.murata.com/products/productdetail?partno=GRM155R61H104KE14%23" (at 340.36 163.83 0)
      (effects (font (size 1.27 1.27)) hide)
    )
    (property "Manufacturer" "Murata" (at 330.2 158.75 0)
      (effects (font (size 1.524 1.524)) (justify left) hide)
    )
    (property "MPN" "GRM155R61H104KE14D" (at 332.74 158.75 0)
      (effects (font (size 1.524 1.524)) (justify left) hide)
    )
    (property "Val" "100n" (at 342.9 162.5536 90)
      (effects (font (size 1.27 1.27)) (justify right))
    )
    (property "License" "Apache-2.0" (at 363.22 143.51 0)
      (effects (font (size 1.27 1.27) (thickness 0.15)) (justify left bottom) hide)
    )
    (property "Author" "Antmicro" (at 365.76 143.51 0)
      (effects (font (size 1.27 1.27) (thickness 0.15)) (justify left bottom) hide)
    )
    (property "Voltage" "50V" (at 368.3 143.51 0)
      (effects (font (size 1.27 1.27)) (justify left bottom) hide)
    )
    (property "Dielectric" "X5R" (at 370.84 143.51 0)
      (effects (font (size 1.27 1.27)) (justify left bottom) hide)
    )
    (property "Public" "False" (at 373.38 143.51 0)
      (effects (font (size 1.27 1.27)) (justify left bottom) hide)
    )
    (pin "1")
    (pin "2")
    (instances
      (project "ecp5-dc-scm"
        (path ""
          (reference "C29") (unit 1)
        )
      )
    )
  )

  (symbol (lib_id "antmicroCapacitors0402:C_100n_0402") (at 330.2 163.83 90) (unit 1)
    (in_bom yes) (on_board yes) (dnp no) (fields_autoplaced)
    (property "Reference" "C28" (at 332.74 160.0136 90)
      (effects (font (size 1.524 1.524)) (justify right))
    )
    (property "Value" "C_100n_0402" (at 334.01 163.83 0)
      (effects (font (size 1.524 1.524)) hide)
    )
    (property "Footprint" "antmicro-footprints:C_0402_1005Metric" (at 325.12 158.75 0)
      (effects (font (size 1.524 1.524)) (justify left) hide)
    )
    (property "Datasheet" "https://www.murata.com/products/productdetail?partno=GRM155R61H104KE14%23" (at 330.2 163.83 0)
      (effects (font (size 1.27 1.27)) hide)
    )
    (property "Manufacturer" "Murata" (at 320.04 158.75 0)
      (effects (font (size 1.524 1.524)) (justify left) hide)
    )
    (property "MPN" "GRM155R61H104KE14D" (at 322.58 158.75 0)
      (effects (font (size 1.524 1.524)) (justify left) hide)
    )
    (property "Val" "100n" (at 332.74 162.5536 90)
      (effects (font (size 1.27 1.27)) (justify right))
    )
    (property "License" "Apache-2.0" (at 353.06 143.51 0)
      (effects (font (size 1.27 1.27) (thickness 0.15)) (justify left bottom) hide)
    )
    (property "Author" "Antmicro" (at 355.6 143.51 0)
      (effects (font (size 1.27 1.27) (thickness 0.15)) (justify left bottom) hide)
    )
    (property "Voltage" "50V" (at 358.14 143.51 0)
      (effects (font (size 1.27 1.27)) (justify left bottom) hide)
    )
    (property "Dielectric" "X5R" (at 360.68 143.51 0)
      (effects (font (size 1.27 1.27)) (justify left bottom) hide)
    )
    (property "Public" "False" (at 363.22 143.51 0)
      (effects (font (size 1.27 1.27)) (justify left bottom) hide)
    )
    (pin "1")
    (pin "2")
    (instances
      (project "ecp5-dc-scm"
        (path ""
          (reference "C28") (unit 1)
        )
      )
    )
  )

  (symbol (lib_id "antmicroCapacitors0402:C_100n_0402") (at 321.31 163.83 90) (unit 1)
    (in_bom yes) (on_board yes) (dnp no) (fields_autoplaced)
    (property "Reference" "C27" (at 323.85 160.0136 90)
      (effects (font (size 1.524 1.524)) (justify right))
    )
    (property "Value" "C_100n_0402" (at 325.12 163.83 0)
      (effects (font (size 1.524 1.524)) hide)
    )
    (property "Footprint" "antmicro-footprints:C_0402_1005Metric" (at 316.23 158.75 0)
      (effects (font (size 1.524 1.524)) (justify left) hide)
    )
    (property "Datasheet" "https://www.murata.com/products/productdetail?partno=GRM155R61H104KE14%23" (at 321.31 163.83 0)
      (effects (font (size 1.27 1.27)) hide)
    )
    (property "Manufacturer" "Murata" (at 311.15 158.75 0)
      (effects (font (size 1.524 1.524)) (justify left) hide)
    )
    (property "MPN" "GRM155R61H104KE14D" (at 313.69 158.75 0)
      (effects (font (size 1.524 1.524)) (justify left) hide)
    )
    (property "Val" "100n" (at 323.85 162.5536 90)
      (effects (font (size 1.27 1.27)) (justify right))
    )
    (property "License" "Apache-2.0" (at 344.17 143.51 0)
      (effects (font (size 1.27 1.27) (thickness 0.15)) (justify left bottom) hide)
    )
    (property "Author" "Antmicro" (at 346.71 143.51 0)
      (effects (font (size 1.27 1.27) (thickness 0.15)) (justify left bottom) hide)
    )
    (property "Voltage" "50V" (at 349.25 143.51 0)
      (effects (font (size 1.27 1.27)) (justify left bottom) hide)
    )
    (property "Dielectric" "X5R" (at 351.79 143.51 0)
      (effects (font (size 1.27 1.27)) (justify left bottom) hide)
    )
    (property "Public" "False" (at 354.33 143.51 0)
      (effects (font (size 1.27 1.27)) (justify left bottom) hide)
    )
    (pin "1")
    (pin "2")
    (instances
      (project "ecp5-dc-scm"
        (path ""
          (reference "C27") (unit 1)
        )
      )
    )
  )

  (symbol (lib_id "antmicropower:GND") (at 321.31 166.37 0) (mirror y) (unit 1)
    (in_bom yes) (on_board yes) (dnp no)
    (property "Reference" "#PWR08" (at 321.31 172.72 0)
      (effects (font (size 1.27 1.27)) hide)
    )
    (property "Value" "GND" (at 321.183 170.7642 0)
      (effects (font (size 1.27 1.27)))
    )
    (property "Footprint" "" (at 321.31 166.37 0)
      (effects (font (size 1.27 1.27)) hide)
    )
    (property "Datasheet" "" (at 321.31 166.37 0)
      (effects (font (size 1.27 1.27)) hide)
    )
    (property "Author" "Antmicro" (at 312.42 173.99 0)
      (effects (font (size 1.27 1.27) (thickness 0.15)) (justify left bottom) hide)
    )
    (property "License" "Apache-2.0" (at 312.42 176.53 0)
      (effects (font (size 1.27 1.27) (thickness 0.15)) (justify left bottom) hide)
    )
    (pin "1")
    (instances
      (project "ecp5-dc-scm"
        (path ""
          (reference "#PWR08") (unit 1)
        )
      )
    )
  )

  (symbol (lib_id "antmicroModularConnectorsJacksWithMagnetics:L834-1G1T-S7") (at 355.6 124.46 0) (unit 1)
    (in_bom yes) (on_board yes) (dnp no)
    (property "Reference" "J1" (at 359.41 116.84 0)
      (effects (font (size 1.27 1.27)) (justify left))
    )
    (property "Value" "L834-1G1T-S7" (at 359.41 119.38 0)
      (effects (font (size 1.27 1.27)) (justify left))
    )
    (property "Footprint" "antmicro-footprints:RJ45_BEL_L834-1G1T-S7" (at 355.6 124.46 0)
      (effects (font (size 1.27 1.27)) (justify left bottom) hide)
    )
    (property "Datasheet" "https://www.belfuse.com/resources/drawings/magneticsolutions/dr-mag-l834-1g1t-s7.pdf" (at 355.6 124.46 0)
      (effects (font (size 1.27 1.27)) (justify left bottom) hide)
    )
    (property "MPN" "L834-1G1T-S7" (at 355.6 124.46 0)
      (effects (font (size 1.27 1.27)) (justify left bottom) hide)
    )
    (property "Manufacturer" "Bel Fuse" (at 355.6 124.46 0)
      (effects (font (size 1.27 1.27)) (justify left bottom) hide)
    )
    (property "Author" "Antmicro" (at 388.62 142.24 0)
      (effects (font (size 1.27 1.27) (thickness 0.15)) (justify left bottom) hide)
    )
    (property "License" "Apache-2.0" (at 388.62 144.78 0)
      (effects (font (size 1.27 1.27) (thickness 0.15)) (justify left bottom) hide)
    )
    (pin "1")
    (pin "10")
    (pin "11")
    (pin "12")
    (pin "13")
    (pin "14")
    (pin "2")
    (pin "3")
    (pin "4")
    (pin "5")
    (pin "6")
    (pin "7")
    (pin "8")
    (pin "9")
    (pin "SH")
    (pin "15")
    (pin "16")
    (instances
      (project "ecp5-dc-scm"
        (path ""
          (reference "J1") (unit 1)
        )
      )
    )
  )

  (symbol (lib_id "antmicroInterfaceControllers:KSZ9031RNXCA") (at 184.15 111.76 0) (unit 1)
    (in_bom yes) (on_board yes) (dnp no)
    (property "Reference" "U1" (at 189.23 107.95 0)
      (effects (font (size 1.27 1.27) (thickness 0.15)))
    )
    (property "Value" "KSZ9031RNXCA" (at 260.35 119.38 0)
      (effects (font (size 1.27 1.27) (thickness 0.15)) (justify left bottom) hide)
    )
    (property "Footprint" "antmicro-footprints:QFN-48-1EP_7x7x0.9mm_P0.5mm_EP3.5x3.5mm" (at 260.35 121.92 0)
      (effects (font (size 1.27 1.27) (thickness 0.15)) (justify left bottom) hide)
    )
    (property "Datasheet" "http://ww1.microchip.com/downloads/en/DeviceDoc/00002117F.pdf" (at 260.35 124.46 0)
      (effects (font (size 1.27 1.27) (thickness 0.15)) (justify left bottom) hide)
    )
    (property "Manufacturer" "Microchip Technology" (at 260.35 127 0)
      (effects (font (size 1.27 1.27) (thickness 0.15)) (justify left bottom) hide)
    )
    (property "MPN" "KSZ9031RNXCA" (at 217.17 107.95 0)
      (effects (font (size 1.27 1.27) (thickness 0.15)))
    )
    (property "Author" "Antmicro" (at 260.35 132.08 0)
      (effects (font (size 1.27 1.27) (thickness 0.15)) (justify left bottom) hide)
    )
    (property "License" "Apache-2.0" (at 260.35 134.62 0)
      (effects (font (size 1.27 1.27) (thickness 0.15)) (justify left bottom) hide)
    )
    (pin "41")
    (pin "40")
    (pin "6")
    (pin "22")
    (pin "27")
    (pin "35")
    (pin "31")
    (pin "44")
    (pin "46")
    (pin "17")
    (pin "16")
    (pin "33")
    (pin "9")
    (pin "48")
    (pin "29")
    (pin "30")
    (pin "26")
    (pin "5")
    (pin "4")
    (pin "25")
    (pin "8")
    (pin "47")
    (pin "23")
    (pin "20")
    (pin "43")
    (pin "45")
    (pin "32")
    (pin "34")
    (pin "12")
    (pin "13")
    (pin "2")
    (pin "14")
    (pin "1")
    (pin "18")
    (pin "15")
    (pin "19")
    (pin "3")
    (pin "7")
    (pin "37")
    (pin "42")
    (pin "38")
    (pin "21")
    (pin "24")
    (pin "28")
    (pin "39")
    (pin "49")
    (pin "11")
    (pin "10")
    (pin "36")
    (instances
      (project "ecp5-dc-scm"
        (path ""
          (reference "U1") (unit 1)
        )
      )
    )
  )

  (symbol (lib_id "antmicropower:GND") (at 349.25 166.37 0) (mirror y) (unit 1)
    (in_bom yes) (on_board yes) (dnp no)
    (property "Reference" "#PWR060" (at 349.25 172.72 0)
      (effects (font (size 1.27 1.27)) hide)
    )
    (property "Value" "GND" (at 349.123 170.7642 0)
      (effects (font (size 1.27 1.27)))
    )
    (property "Footprint" "" (at 349.25 166.37 0)
      (effects (font (size 1.27 1.27)) hide)
    )
    (property "Datasheet" "" (at 349.25 166.37 0)
      (effects (font (size 1.27 1.27)) hide)
    )
    (property "Author" "Antmicro" (at 340.36 173.99 0)
      (effects (font (size 1.27 1.27) (thickness 0.15)) (justify left bottom) hide)
    )
    (property "License" "Apache-2.0" (at 340.36 176.53 0)
      (effects (font (size 1.27 1.27) (thickness 0.15)) (justify left bottom) hide)
    )
    (pin "1")
    (instances
      (project "ecp5-dc-scm"
        (path ""
          (reference "#PWR060") (unit 1)
        )
      )
    )
  )

  (symbol (lib_id "antmicropower:PWR_FLAG") (at 287.02 106.68 0) (unit 1)
    (in_bom yes) (on_board yes) (dnp no)
    (property "Reference" "#FLG03" (at 287.02 104.775 0)
      (effects (font (size 1.27 1.27)) hide)
    )
    (property "Value" "PWR_FLAG" (at 287.02 102.87 0)
      (effects (font (size 1.27 1.27)))
    )
    (property "Footprint" "" (at 287.02 106.68 0)
      (effects (font (size 1.27 1.27)) hide)
    )
    (property "Datasheet" "" (at 287.02 106.68 0)
      (effects (font (size 1.27 1.27)) hide)
    )
    (pin "1")
    (instances
      (project "ecp5-dc-scm"
        (path ""
          (reference "#FLG03") (unit 1)
        )
      )
    )
  )

  (symbol (lib_id "antmicropower:PWR_FLAG") (at 125.73 114.3 0) (unit 1)
    (in_bom yes) (on_board yes) (dnp no)
    (property "Reference" "#FLG04" (at 125.73 112.395 0)
      (effects (font (size 1.27 1.27)) hide)
    )
    (property "Value" "PWR_FLAG" (at 125.73 110.49 0)
      (effects (font (size 1.27 1.27)))
    )
    (property "Footprint" "" (at 125.73 114.3 0)
      (effects (font (size 1.27 1.27)) hide)
    )
    (property "Datasheet" "" (at 125.73 114.3 0)
      (effects (font (size 1.27 1.27)) hide)
    )
    (pin "1")
    (instances
      (project "ecp5-dc-scm"
        (path ""
          (reference "#FLG04") (unit 1)
        )
      )
    )
  )

  (symbol (lib_id "antmicropower:GND") (at 340.36 166.37 0) (mirror y) (unit 1)
    (in_bom yes) (on_board yes) (dnp no)
    (property "Reference" "#PWR047" (at 340.36 172.72 0)
      (effects (font (size 1.27 1.27)) hide)
    )
    (property "Value" "GND" (at 340.233 170.7642 0)
      (effects (font (size 1.27 1.27)))
    )
    (property "Footprint" "" (at 340.36 166.37 0)
      (effects (font (size 1.27 1.27)) hide)
    )
    (property "Datasheet" "" (at 340.36 166.37 0)
      (effects (font (size 1.27 1.27)) hide)
    )
    (property "Author" "Antmicro" (at 331.47 173.99 0)
      (effects (font (size 1.27 1.27) (thickness 0.15)) (justify left bottom) hide)
    )
    (property "License" "Apache-2.0" (at 331.47 176.53 0)
      (effects (font (size 1.27 1.27) (thickness 0.15)) (justify left bottom) hide)
    )
    (pin "1")
    (instances
      (project "ecp5-dc-scm"
        (path ""
          (reference "#PWR047") (unit 1)
        )
      )
    )
  )

  (symbol (lib_id "antmicropower:PWR_FLAG") (at 293.37 129.54 0) (unit 1)
    (in_bom yes) (on_board yes) (dnp no)
    (property "Reference" "#FLG02" (at 293.37 127.635 0)
      (effects (font (size 1.27 1.27)) hide)
    )
    (property "Value" "PWR_FLAG" (at 293.37 125.73 0)
      (effects (font (size 1.27 1.27)))
    )
    (property "Footprint" "" (at 293.37 129.54 0)
      (effects (font (size 1.27 1.27)) hide)
    )
    (property "Datasheet" "" (at 293.37 129.54 0)
      (effects (font (size 1.27 1.27)) hide)
    )
    (pin "1")
    (instances
      (project "ecp5-dc-scm"
        (path ""
          (reference "#FLG02") (unit 1)
        )
      )
    )
  )

  (symbol (lib_id "antmicropower:GND") (at 330.2 166.37 0) (mirror y) (unit 1)
    (in_bom yes) (on_board yes) (dnp no)
    (property "Reference" "#PWR045" (at 330.2 172.72 0)
      (effects (font (size 1.27 1.27)) hide)
    )
    (property "Value" "GND" (at 330.073 170.7642 0)
      (effects (font (size 1.27 1.27)))
    )
    (property "Footprint" "" (at 330.2 166.37 0)
      (effects (font (size 1.27 1.27)) hide)
    )
    (property "Datasheet" "" (at 330.2 166.37 0)
      (effects (font (size 1.27 1.27)) hide)
    )
    (property "Author" "Antmicro" (at 321.31 173.99 0)
      (effects (font (size 1.27 1.27) (thickness 0.15)) (justify left bottom) hide)
    )
    (property "License" "Apache-2.0" (at 321.31 176.53 0)
      (effects (font (size 1.27 1.27) (thickness 0.15)) (justify left bottom) hide)
    )
    (pin "1")
    (instances
      (project "ecp5-dc-scm"
        (path ""
          (reference "#PWR045") (unit 1)
        )
      )
    )
  )

  (symbol (lib_id "antmicroOscillators:Oscillator_25MHz_ESC_2016MV") (at 199.39 194.31 0) (unit 1)
    (in_bom yes) (on_board yes) (dnp no)
    (property "Reference" "Y5" (at 203.2 190.5 0)
      (effects (font (size 1.27 1.27) (thickness 0.15)))
    )
    (property "Value" "Oscillator_25MHz_ESC_2016MV" (at 224.79 207.01 0)
      (effects (font (size 1.27 1.27) (thickness 0.15)) (justify left bottom) hide)
    )
    (property "Footprint" "antmicro-footprints:Oscillator_SMD_ECS_2016MV_2x1.6x0.85mm" (at 224.79 209.55 0)
      (effects (font (size 1.27 1.27) (thickness 0.15)) (justify left bottom) hide)
    )
    (property "Datasheet" "https://ecsxtal.com/store/pdf/ECS-2016MV.pdf" (at 224.79 212.09 0)
      (effects (font (size 1.27 1.27) (thickness 0.15)) (justify left bottom) hide)
    )
    (property "MPN" "ECS-2016MV-250-CN-TR" (at 212.09 203.2 0)
      (effects (font (size 1.27 1.27) (thickness 0.15)))
    )
    (property "Manufacturer" "ECS Inc. International" (at 224.79 201.93 0)
      (effects (font (size 1.27 1.27) (thickness 0.15)) (justify left bottom) hide)
    )
    (property "Val" "25 MHz" (at 212.09 190.5 0)
      (effects (font (size 1.27 1.27) (thickness 0.15)))
    )
    (property "Author" "Antmicro" (at 224.79 214.63 0)
      (effects (font (size 1.27 1.27) (thickness 0.15)) (justify left bottom) hide)
    )
    (property "License" "Apache-2.0" (at 224.79 217.17 0)
      (effects (font (size 1.27 1.27) (thickness 0.15)) (justify left bottom) hide)
    )
    (pin "3")
    (pin "1")
    (pin "4")
    (pin "2")
    (instances
      (project "ecp5-dc-scm"
        (path ""
          (reference "Y5") (unit 1)
        )
      )
    )
  )
)
